FILE_TYPE = MACRO_DRAWING;
SET COLOR_WIRE YELLOW;
SET COLOR_PROP ORANGE;
SET COLOR_DOT WHITE;
SET COLOR_ARC YELLOW;
SET COLOR_BODY GREEN;
SET COLOR_NOTE PURPLE;
SET PROP_DISPLAY VALUE;
SET PAGE_NUMBER P197;
FORCEADD UNIVERSAL_GND..1
(100 1675);
FORCEPROP 3 LASTPIN (100 1725) SIG_NAME GND\g
J 0
(110 1735);
DISPLAY 0.659574 (110 1735);
PAINT MONO (110 1735);
DISPLAY INVISIBLE (110 1735);
FORCEPROP 2 LAST CDS_LIB pure_quanta_power
J 0
(100 1675);
DISPLAY INVISIBLE (100 1675);
FORCEPROP 1 LAST HDL_POWER GND
J 1
(125 1600);
DISPLAY 0.872340 (125 1600);
PAINT GREEN (125 1600);
DISPLAY INVISIBLE (125 1600);
FORCEPROP 1 LAST PATH I1
J 0
(175 1675);
DISPLAY 0.872340 (175 1675);
PAINT AQUA (175 1675);
DISPLAY INVISIBLE (175 1675);
FORCEADD OFFPAGE..5
(1100 2250);
FORCEPROP 2 LAST $XR0 217 
J 0
(845 2250);
DISPLAY 0.638298 (845 2250);
PAINT MONO (845 2250);
FORCEPROP 2 LAST CDS_LIB standard
J 0
(1100 2250);
DISPLAY INVISIBLE (1100 2250);
FORCEPROP 1 LAST OFFPAGE TRUE
J 0
(1425 2125);
DISPLAY 0.872340 (1425 2125);
PAINT GREEN (1425 2125);
DISPLAY INVISIBLE (1425 2125);
FORCEPROP 1 LAST COMMENT_BODY TRUE
J 0
(1200 2175);
DISPLAY 0.872340 (1200 2175);
PAINT GREEN (1200 2175);
DISPLAY INVISIBLE (1200 2175);
FORCEPROP 2 LAST PATH I10
J 0
(850 2300);
DISPLAY 0.680851 (850 2300);
DISPLAY INVISIBLE (850 2300);
FORCEADD UNIVERSAL_GND..1
(975 2450);
FORCEPROP 3 LASTPIN (975 2500) SIG_NAME GND\g
J 0
(985 2510);
DISPLAY 0.659574 (985 2510);
PAINT MONO (985 2510);
DISPLAY INVISIBLE (985 2510);
FORCEPROP 2 LAST CDS_LIB pure_quanta_power
J 0
(975 2450);
DISPLAY INVISIBLE (975 2450);
FORCEPROP 1 LAST HDL_POWER GND
J 1
(1000 2375);
DISPLAY 0.872340 (1000 2375);
PAINT GREEN (1000 2375);
DISPLAY INVISIBLE (1000 2375);
FORCEPROP 1 LAST PATH I11
J 0
(1050 2450);
DISPLAY 0.872340 (1050 2450);
PAINT AQUA (1050 2450);
DISPLAY INVISIBLE (1050 2450);
FORCEADD Q_CAP..1
(975 2650);
FORCEPROP 1 LAST LOCATION PC432
J 0
(1025 2750);
DISPLAY 0.489362 (1025 2750);
PAINT SKYBLUE (1025 2750);
FORCEPROP 0 LAST $SEC 1
J 0
(1025 2800);
DISPLAY 0.680851 (1025 2800);
PAINT MONO (1025 2800);
DISPLAY INVISIBLE (1025 2800);
FORCEPROP 0 LAST CDS_SEC 1
J 0
(1025 2800);
DISPLAY 1.021277 (1025 2800);
DISPLAY INVISIBLE (1025 2800);
FORCEPROP 1 LASTPIN (975 2750) $PN 1
J 0
(985 2730);
DISPLAY 0.489362 (985 2730);
PAINT MONO (985 2730);
FORCEPROP 1 LASTPIN (975 2550) $PN 2
J 0
(985 2530);
DISPLAY 0.489362 (985 2530);
PAINT MONO (985 2530);
FORCEPROP 1 LAST TOLERANCE 10%
J 0
(1025 2600);
DISPLAY 0.489362 (1025 2600);
PAINT SKYBLUE (1025 2600);
FORCEPROP 1 LAST VALUE 2.2UF
J 0
(1025 2700);
DISPLAY 0.489362 (1025 2700);
PAINT SKYBLUE (1025 2700);
FORCEPROP 1 LAST VOLTAGE 10V
J 0
(1025 2650);
DISPLAY 0.489362 (1025 2650);
PAINT SKYBLUE (1025 2650);
FORCEPROP 1 LAST PACK_TYPE C0402
J 0
(1025 2450);
DISPLAY 0.489362 (1025 2450);
PAINT SKYBLUE (1025 2450);
FORCEPROP 1 LAST MATERIAL X6S
J 0
(1025 2550);
DISPLAY 0.489362 (1025 2550);
PAINT SKYBLUE (1025 2550);
FORCEPROP 2 LAST CDS_LIB pure_quanta
J 0
(975 2650);
DISPLAY INVISIBLE (975 2650);
FORCEPROP 1 LAST PATH I12
J 0
(1025 2800);
DISPLAY 0.978723 (1025 2800);
PAINT WHITE (1025 2800);
DISPLAY INVISIBLE (1025 2800);
FORCEPROP 1 LAST PART_NUMBER CH5222KEB01
J 0
(1025 2500);
DISPLAY 0.489362 (1025 2500);
PAINT SKYBLUE (1025 2500);
DISPLAY INVISIBLE (1025 2500);
FORCEADD Q_RES..2
(975 3200);
FORCEPROP 1 LAST LOCATION PR276
J 0
(1020 3325);
DISPLAY 0.489362 (1020 3325);
PAINT SKYBLUE (1020 3325);
FORCEPROP 0 LAST $SEC 1
J 0
(1025 3375);
DISPLAY 0.680851 (1025 3375);
PAINT MONO (1025 3375);
DISPLAY INVISIBLE (1025 3375);
FORCEPROP 0 LAST CDS_SEC 1
J 0
(1025 3375);
DISPLAY 1.021277 (1025 3375);
DISPLAY INVISIBLE (1025 3375);
FORCEPROP 1 LASTPIN (975 3300) $PN 1
J 0
(980 3262);
DISPLAY 0.489362 (980 3262);
PAINT MONO (980 3262);
FORCEPROP 1 LASTPIN (975 3100) $PN 2
J 0
(980 3110);
DISPLAY 0.489362 (980 3110);
PAINT MONO (980 3110);
FORCEPROP 1 LAST WATTAGE 1/16W
J 0
(1025 3175);
DISPLAY 0.489362 (1025 3175);
PAINT SKYBLUE (1025 3175);
FORCEPROP 1 LAST MATERIAL CHIP
J 0
(1025 3125);
DISPLAY 0.489362 (1025 3125);
PAINT SKYBLUE (1025 3125);
FORCEPROP 1 LAST TOLERANCE 1%
J 0
(1025 3225);
DISPLAY 0.489362 (1025 3225);
PAINT SKYBLUE (1025 3225);
FORCEPROP 1 LAST VALUE 2.2
J 0
(1025 3275);
DISPLAY 0.489362 (1025 3275);
PAINT SKYBLUE (1025 3275);
FORCEPROP 1 LAST PACK_TYPE 0402LF
J 0
(1025 3025);
DISPLAY 0.489362 (1025 3025);
PAINT SKYBLUE (1025 3025);
FORCEPROP 2 LAST CDS_LIB pure_quanta
J 0
(975 3200);
DISPLAY INVISIBLE (975 3200);
FORCEPROP 1 LAST PATH I13
J 0
(1025 3375);
DISPLAY 0.978723 (1025 3375);
PAINT WHITE (1025 3375);
DISPLAY INVISIBLE (1025 3375);
FORCEPROP 1 LAST PART_NUMBER CS-2202FB01
J 0
(1025 3075);
DISPLAY 0.489362 (1025 3075);
PAINT SKYBLUE (1025 3075);
DISPLAY INVISIBLE (1025 3075);
FORCEADD VCC_CORE..1
(975 3600);
FORCEPROP 3 LASTPIN (975 3550) SIG_NAME PVDDCR_CPU1_P1_PVCC\g
J 0
(985 3560);
DISPLAY 0.659574 (985 3560);
PAINT MONO (985 3560);
DISPLAY INVISIBLE (985 3560);
FORCEPROP 1 LAST HDL_POWER PVDDCR_CPU1_P1_PVCC
J 1
(975 3650);
DISPLAY 0.489362 (975 3650);
PAINT GREEN (975 3650);
FORCEPROP 2 LAST CDS_LIB pure_quanta_power
J 0
(975 3600);
DISPLAY INVISIBLE (975 3600);
FORCEPROP 1 LAST PATH I14
J 0
(1025 3625);
DISPLAY 0.872340 (1025 3625);
PAINT AQUA (1025 3625);
DISPLAY INVISIBLE (1025 3625);
FORCEADD UNIVERSAL_GND..1
(1325 2950);
FORCEPROP 3 LASTPIN (1325 3000) SIG_NAME GND\g
J 0
(1335 3010);
DISPLAY 0.659574 (1335 3010);
PAINT MONO (1335 3010);
DISPLAY INVISIBLE (1335 3010);
FORCEPROP 2 LAST CDS_LIB pure_quanta_power
J 0
(1325 2950);
DISPLAY INVISIBLE (1325 2950);
FORCEPROP 1 LAST HDL_POWER GND
J 1
(1350 2875);
DISPLAY 0.872340 (1350 2875);
PAINT GREEN (1350 2875);
DISPLAY INVISIBLE (1350 2875);
FORCEPROP 1 LAST PATH I15
J 0
(1400 2950);
DISPLAY 0.872340 (1400 2950);
PAINT AQUA (1400 2950);
DISPLAY INVISIBLE (1400 2950);
FORCEADD Q_CAP..1
(1325 3225);
FORCEPROP 1 LAST LOCATION PC434_IOP1_2
J 0
(1375 3325);
DISPLAY 0.489362 (1375 3325);
PAINT SKYBLUE (1375 3325);
FORCEPROP 0 LAST $SEC 1
J 0
(1375 3375);
DISPLAY 0.680851 (1375 3375);
PAINT MONO (1375 3375);
DISPLAY INVISIBLE (1375 3375);
FORCEPROP 0 LAST CDS_SEC 1
J 0
(1375 3375);
DISPLAY 1.021277 (1375 3375);
DISPLAY INVISIBLE (1375 3375);
FORCEPROP 1 LASTPIN (1325 3325) $PN 1
J 0
(1335 3305);
DISPLAY 0.489362 (1335 3305);
PAINT MONO (1335 3305);
FORCEPROP 1 LASTPIN (1325 3125) $PN 2
J 0
(1335 3105);
DISPLAY 0.489362 (1335 3105);
PAINT MONO (1335 3105);
FORCEPROP 1 LAST PACK_TYPE C0402
J 0
(1375 3025);
DISPLAY 0.489362 (1375 3025);
PAINT SKYBLUE (1375 3025);
FORCEPROP 1 LAST VOLTAGE 10V
J 0
(1375 3225);
DISPLAY 0.489362 (1375 3225);
PAINT SKYBLUE (1375 3225);
FORCEPROP 1 LAST VALUE 2.2UF
J 0
(1375 3275);
DISPLAY 0.489362 (1375 3275);
PAINT SKYBLUE (1375 3275);
FORCEPROP 1 LAST TOLERANCE 10%
J 0
(1375 3175);
DISPLAY 0.489362 (1375 3175);
PAINT SKYBLUE (1375 3175);
FORCEPROP 1 LAST MATERIAL X6S
J 0
(1375 3125);
DISPLAY 0.489362 (1375 3125);
PAINT SKYBLUE (1375 3125);
FORCEPROP 2 LAST CDS_LIB pure_quanta
J 0
(1325 3225);
DISPLAY INVISIBLE (1325 3225);
FORCEPROP 1 LAST PATH I16
J 0
(1375 3375);
DISPLAY 0.978723 (1375 3375);
PAINT WHITE (1375 3375);
DISPLAY INVISIBLE (1375 3375);
FORCEPROP 1 LAST PART_NUMBER CH5222KEB01
J 0
(1375 3075);
DISPLAY 0.489362 (1375 3075);
PAINT SKYBLUE (1375 3075);
DISPLAY INVISIBLE (1375 3075);
FORCEADD UNIVERSAL_GND..1
(3300 1525);
FORCEPROP 3 LASTPIN (3300 1575) SIG_NAME GND\g
J 0
(3310 1585);
DISPLAY 0.659574 (3310 1585);
PAINT MONO (3310 1585);
DISPLAY INVISIBLE (3310 1585);
FORCEPROP 2 LAST CDS_LIB pure_quanta_power
J 0
(3300 1525);
PAINT MONO (3300 1525);
DISPLAY INVISIBLE (3300 1525);
FORCEPROP 1 LAST HDL_POWER GND
J 1
(3325 1450);
DISPLAY 0.872340 (3325 1450);
PAINT GREEN (3325 1450);
DISPLAY INVISIBLE (3325 1450);
FORCEPROP 1 LAST PATH I17
J 0
(3375 1525);
DISPLAY 0.872340 (3375 1525);
PAINT AQUA (3375 1525);
DISPLAY INVISIBLE (3375 1525);
FORCEADD UNIVERSAL_GND..1
(4025 1325);
FORCEPROP 3 LASTPIN (4025 1375) SIG_NAME GND\g
J 0
(4035 1385);
DISPLAY 0.659574 (4035 1385);
PAINT MONO (4035 1385);
DISPLAY INVISIBLE (4035 1385);
FORCEPROP 2 LAST CDS_LIB pure_quanta_power
J 0
(4025 1325);
DISPLAY INVISIBLE (4025 1325);
FORCEPROP 1 LAST HDL_POWER GND
J 1
(4050 1250);
DISPLAY 0.872340 (4050 1250);
PAINT GREEN (4050 1250);
DISPLAY INVISIBLE (4050 1250);
FORCEPROP 1 LAST PATH I18
J 0
(4100 1325);
DISPLAY 0.872340 (4100 1325);
PAINT AQUA (4100 1325);
DISPLAY INVISIBLE (4100 1325);
FORCEADD Q_RES..2
(4025 1550);
FORCEPROP 1 LAST LOCATION PR489
J 0
(4070 1675);
DISPLAY 0.489362 (4070 1675);
PAINT SKYBLUE (4070 1675);
FORCEPROP 0 LAST $SEC 1
J 0
(4075 1725);
DISPLAY 0.680851 (4075 1725);
PAINT MONO (4075 1725);
DISPLAY INVISIBLE (4075 1725);
FORCEPROP 0 LAST CDS_SEC 1
J 0
(4075 1725);
DISPLAY 1.021277 (4075 1725);
DISPLAY INVISIBLE (4075 1725);
FORCEPROP 1 LASTPIN (4025 1650) $PN 1
J 0
(4030 1612);
DISPLAY 0.489362 (4030 1612);
PAINT MONO (4030 1612);
FORCEPROP 1 LASTPIN (4025 1450) $PN 2
J 0
(4030 1460);
DISPLAY 0.489362 (4030 1460);
PAINT MONO (4030 1460);
FORCEPROP 1 LAST PACK_TYPE 0402LF
J 0
(4065 1375);
DISPLAY 0.489362 (4065 1375);
PAINT SKYBLUE (4065 1375);
FORCEPROP 1 LAST MATERIAL EMPTY
J 0
(4065 1475);
DISPLAY 0.489362 (4065 1475);
PAINT RED (4065 1475);
FORCEPROP 1 LAST WATTAGE 1/8W
J 0
(4065 1525);
DISPLAY 0.489362 (4065 1525);
PAINT SKYBLUE (4065 1525);
FORCEPROP 1 LAST VALUE 1.5
J 0
(4070 1625);
DISPLAY 0.489362 (4070 1625);
PAINT SKYBLUE (4070 1625);
FORCEPROP 1 LAST TOLERANCE 1%
J 0
(4070 1575);
DISPLAY 0.489362 (4070 1575);
PAINT SKYBLUE (4070 1575);
FORCEPROP 2 LAST CDS_LIB pure_quanta
J 0
(4025 1550);
DISPLAY INVISIBLE (4025 1550);
FORCEPROP 1 LAST PATH I19
J 0
(4075 1725);
DISPLAY 0.978723 (4075 1725);
PAINT WHITE (4075 1725);
DISPLAY INVISIBLE (4075 1725);
FORCEPROP 1 LAST PART_NUMBER CS-1504FB00
J 0
(4065 1425);
DISPLAY 0.489362 (4065 1425);
PAINT SKYBLUE (4065 1425);
DISPLAY INVISIBLE (4065 1425);
FORCEADD UNIVERSAL_GND..1
(100 4425);
FORCEPROP 3 LASTPIN (100 4475) SIG_NAME GND\g
J 0
(110 4485);
DISPLAY 0.659574 (110 4485);
PAINT MONO (110 4485);
DISPLAY INVISIBLE (110 4485);
FORCEPROP 2 LAST CDS_LIB pure_quanta_power
J 0
(100 4425);
DISPLAY INVISIBLE (100 4425);
FORCEPROP 1 LAST HDL_POWER GND
J 1
(125 4350);
DISPLAY 0.872340 (125 4350);
PAINT GREEN (125 4350);
DISPLAY INVISIBLE (125 4350);
FORCEPROP 1 LAST PATH I2
J 0
(175 4425);
DISPLAY 0.872340 (175 4425);
PAINT AQUA (175 4425);
DISPLAY INVISIBLE (175 4425);
FORCEADD Q_CAP..1
(4025 2050);
FORCEPROP 1 LAST LOCATION PC175
J 0
(4075 2150);
DISPLAY 0.489362 (4075 2150);
PAINT SKYBLUE (4075 2150);
FORCEPROP 0 LAST $SEC 1
J 0
(4075 2200);
DISPLAY 0.680851 (4075 2200);
PAINT MONO (4075 2200);
DISPLAY INVISIBLE (4075 2200);
FORCEPROP 0 LAST CDS_SEC 1
J 0
(4075 2200);
DISPLAY 1.021277 (4075 2200);
DISPLAY INVISIBLE (4075 2200);
FORCEPROP 1 LASTPIN (4025 2150) $PN 1
J 0
(4035 2130);
DISPLAY 0.489362 (4035 2130);
PAINT MONO (4035 2130);
FORCEPROP 1 LASTPIN (4025 1950) $PN 2
J 0
(4035 1930);
DISPLAY 0.489362 (4035 1930);
PAINT MONO (4035 1930);
FORCEPROP 1 LAST VOLTAGE 50V
J 0
(4075 2050);
DISPLAY 0.489362 (4075 2050);
PAINT SKYBLUE (4075 2050);
FORCEPROP 1 LAST VALUE 560PF
J 0
(4075 2100);
DISPLAY 0.489362 (4075 2100);
PAINT SKYBLUE (4075 2100);
FORCEPROP 1 LAST TOLERANCE 10%
J 0
(4075 2000);
DISPLAY 0.489362 (4075 2000);
PAINT SKYBLUE (4075 2000);
FORCEPROP 1 LAST MATERIAL EMPTY
J 0
(4075 1950);
DISPLAY 0.489362 (4075 1950);
PAINT RED (4075 1950);
FORCEPROP 1 LAST PACK_TYPE C0402
J 0
(4075 1850);
DISPLAY 0.489362 (4075 1850);
PAINT SKYBLUE (4075 1850);
FORCEPROP 2 LAST CDS_LIB pure_quanta
J 0
(4025 2050);
DISPLAY INVISIBLE (4025 2050);
FORCEPROP 1 LAST PATH I20
J 0
(4075 2200);
DISPLAY 0.978723 (4075 2200);
PAINT WHITE (4075 2200);
DISPLAY INVISIBLE (4075 2200);
FORCEPROP 1 LAST PART_NUMBER CH1566K1B09
J 0
(4075 1900);
DISPLAY 0.489362 (4075 1900);
PAINT SKYBLUE (4075 1900);
DISPLAY INVISIBLE (4075 1900);
FORCEADD Q_CAP..1
(3475 3175);
FORCEPROP 1 LAST LOCATION PC439_2
J 0
(3525 3275);
DISPLAY 0.489362 (3525 3275);
PAINT SKYBLUE (3525 3275);
FORCEPROP 0 LAST $SEC 1
J 0
(3525 3325);
DISPLAY 0.680851 (3525 3325);
PAINT MONO (3525 3325);
DISPLAY INVISIBLE (3525 3325);
FORCEPROP 0 LAST CDS_SEC 1
J 0
(3525 3325);
DISPLAY 1.021277 (3525 3325);
DISPLAY INVISIBLE (3525 3325);
FORCEPROP 1 LASTPIN (3475 3275) $PN 1
J 0
(3485 3255);
DISPLAY 0.489362 (3485 3255);
PAINT MONO (3485 3255);
FORCEPROP 1 LASTPIN (3475 3075) $PN 2
J 0
(3485 3055);
DISPLAY 0.489362 (3485 3055);
PAINT MONO (3485 3055);
FORCEPROP 1 LAST VOLTAGE 25V
J 0
(3525 3175);
DISPLAY 0.489362 (3525 3175);
PAINT SKYBLUE (3525 3175);
FORCEPROP 1 LAST VALUE 0.1UF
J 0
(3525 3225);
DISPLAY 0.489362 (3525 3225);
PAINT SKYBLUE (3525 3225);
FORCEPROP 1 LAST TOLERANCE 10%
J 0
(3525 3125);
DISPLAY 0.489362 (3525 3125);
PAINT SKYBLUE (3525 3125);
FORCEPROP 1 LAST MATERIAL X7R
J 0
(3525 3075);
DISPLAY 0.489362 (3525 3075);
PAINT SKYBLUE (3525 3075);
FORCEPROP 1 LAST PACK_TYPE 0402
J 0
(3525 2975);
DISPLAY 0.489362 (3525 2975);
PAINT SKYBLUE (3525 2975);
FORCEPROP 2 LAST CDS_LIB pure_quanta
J 0
(3475 3175);
DISPLAY INVISIBLE (3475 3175);
FORCEPROP 1 LAST PATH I21
J 0
(3525 3325);
DISPLAY 0.978723 (3525 3325);
PAINT WHITE (3525 3325);
DISPLAY INVISIBLE (3525 3325);
FORCEPROP 1 LAST PART_NUMBER CH4104K1B00
J 0
(3525 3025);
DISPLAY 0.489362 (3525 3025);
PAINT SKYBLUE (3525 3025);
DISPLAY INVISIBLE (3525 3025);
FORCEADD Q_RES..1
(3925 2600);
FORCEPROP 1 LAST LOCATION PR278
J 0
(3875 2650);
DISPLAY 0.489362 (3875 2650);
PAINT SKYBLUE (3875 2650);
FORCEPROP 0 LAST $SEC 1
J 0
(4100 2675);
DISPLAY 0.680851 (4100 2675);
PAINT MONO (4100 2675);
DISPLAY INVISIBLE (4100 2675);
FORCEPROP 0 LAST CDS_SEC 1
J 0
(4100 2675);
DISPLAY 1.021277 (4100 2675);
DISPLAY INVISIBLE (4100 2675);
FORCEPROP 1 LASTPIN (3825 2600) $PN 1
J 0
(3837 2612);
DISPLAY 0.787234 (3837 2612);
PAINT MONO (3837 2612);
DISPLAY INVISIBLE (3837 2612);
FORCEPROP 1 LASTPIN (4025 2600) $PN 2
J 0
(3987 2612);
DISPLAY 0.787234 (3987 2612);
PAINT MONO (3987 2612);
DISPLAY INVISIBLE (3987 2612);
FORCEPROP 1 LAST VALUE 5.6
J 2
(3825 2625);
DISPLAY 0.489362 (3825 2625);
PAINT SKYBLUE (3825 2625);
FORCEPROP 1 LAST WATTAGE 1/16W
J 2
(4150 2625);
DISPLAY 0.489362 (4150 2625);
PAINT SKYBLUE (4150 2625);
FORCEPROP 1 LAST MATERIAL CHIP
J 0
(4025 2550);
DISPLAY 0.489362 (4025 2550);
PAINT SKYBLUE (4025 2550);
FORCEPROP 1 LAST TOLERANCE 1%
J 0
(3750 2500);
DISPLAY 0.489362 (3750 2500);
PAINT SKYBLUE (3750 2500);
FORCEPROP 1 LAST PACK_TYPE 0402LF
J 0
(4025 2500);
DISPLAY 0.489362 (4025 2500);
PAINT SKYBLUE (4025 2500);
FORCEPROP 2 LAST CDS_LIB pure_quanta
J 0
(3925 2600);
DISPLAY INVISIBLE (3925 2600);
FORCEPROP 1 LAST PATH I22
J 0
(3875 2750);
DISPLAY 0.978723 (3875 2750);
PAINT WHITE (3875 2750);
DISPLAY INVISIBLE (3875 2750);
FORCEPROP 1 LAST PART_NUMBER CS-5602FB01
J 0
(3625 2550);
DISPLAY 0.489362 (3625 2550);
PAINT SKYBLUE (3625 2550);
DISPLAY INVISIBLE (3625 2550);
FORCEADD Q_CAP..1
(3975 3175);
FORCEPROP 1 LAST LOCATION PC441_2
J 0
(4025 3325);
DISPLAY 0.489362 (4025 3325);
PAINT SKYBLUE (4025 3325);
FORCEPROP 0 LAST $SEC 1
J 0
(4025 3375);
DISPLAY 0.680851 (4025 3375);
PAINT MONO (4025 3375);
DISPLAY INVISIBLE (4025 3375);
FORCEPROP 0 LAST CDS_SEC 1
J 0
(4025 3375);
DISPLAY 1.021277 (4025 3375);
DISPLAY INVISIBLE (4025 3375);
FORCEPROP 1 LASTPIN (3975 3275) $PN 1
J 0
(3985 3255);
DISPLAY 0.489362 (3985 3255);
PAINT MONO (3985 3255);
FORCEPROP 1 LASTPIN (3975 3075) $PN 2
J 0
(3985 3055);
DISPLAY 0.489362 (3985 3055);
PAINT MONO (3985 3055);
FORCEPROP 1 LAST PACK_TYPE C0402
J 0
(4025 3075);
DISPLAY 0.489362 (4025 3075);
PAINT SKYBLUE (4025 3075);
FORCEPROP 1 LAST VOLTAGE 25V
J 0
(4025 3225);
DISPLAY 0.489362 (4025 3225);
PAINT SKYBLUE (4025 3225);
FORCEPROP 1 LAST VALUE 1UF
J 0
(4025 3275);
DISPLAY 0.489362 (4025 3275);
PAINT SKYBLUE (4025 3275);
FORCEPROP 1 LAST TOLERANCE 10%
J 0
(4025 3175);
DISPLAY 0.489362 (4025 3175);
PAINT SKYBLUE (4025 3175);
FORCEPROP 1 LAST MATERIAL X6S
J 0
(4025 3125);
DISPLAY 0.489362 (4025 3125);
PAINT SKYBLUE (4025 3125);
FORCEPROP 2 LAST CDS_LIB pure_quanta
J 0
(3975 3175);
DISPLAY INVISIBLE (3975 3175);
FORCEPROP 1 LAST PATH I23
J 0
(4025 3325);
DISPLAY 0.978723 (4025 3325);
PAINT WHITE (4025 3325);
DISPLAY INVISIBLE (4025 3325);
FORCEPROP 1 LAST PART_NUMBER CH5104KEB02
J 0
(4025 3025);
DISPLAY 0.489362 (4025 3025);
PAINT SKYBLUE (4025 3025);
DISPLAY INVISIBLE (4025 3025);
FORCEADD UNIVERSAL_GND..1
(3300 4275);
FORCEPROP 3 LASTPIN (3300 4325) SIG_NAME GND\g
J 0
(3310 4335);
DISPLAY 0.659574 (3310 4335);
PAINT MONO (3310 4335);
DISPLAY INVISIBLE (3310 4335);
FORCEPROP 2 LAST CDS_LIB pure_quanta_power
J 0
(3300 4275);
PAINT MONO (3300 4275);
DISPLAY INVISIBLE (3300 4275);
FORCEPROP 1 LAST HDL_POWER GND
J 1
(3325 4200);
DISPLAY 0.872340 (3325 4200);
PAINT GREEN (3325 4200);
DISPLAY INVISIBLE (3325 4200);
FORCEPROP 1 LAST PATH I24
J 0
(3375 4275);
DISPLAY 0.872340 (3375 4275);
PAINT AQUA (3375 4275);
DISPLAY INVISIBLE (3375 4275);
FORCEADD UNIVERSAL_GND..1
(4125 4075);
FORCEPROP 3 LASTPIN (4125 4125) SIG_NAME GND\g
J 0
(4135 4135);
DISPLAY 0.659574 (4135 4135);
PAINT MONO (4135 4135);
DISPLAY INVISIBLE (4135 4135);
FORCEPROP 2 LAST CDS_LIB pure_quanta_power
J 0
(4125 4075);
DISPLAY INVISIBLE (4125 4075);
FORCEPROP 1 LAST HDL_POWER GND
J 1
(4150 4000);
DISPLAY 0.872340 (4150 4000);
PAINT GREEN (4150 4000);
DISPLAY INVISIBLE (4150 4000);
FORCEPROP 1 LAST PATH I25
J 0
(4200 4075);
DISPLAY 0.872340 (4200 4075);
PAINT AQUA (4200 4075);
DISPLAY INVISIBLE (4200 4075);
FORCEADD Q_RES..2
(4125 4300);
FORCEPROP 1 LAST LOCATION PR488
J 0
(4170 4425);
DISPLAY 0.489362 (4170 4425);
PAINT SKYBLUE (4170 4425);
FORCEPROP 0 LAST $SEC 1
J 0
(4175 4475);
DISPLAY 0.680851 (4175 4475);
PAINT MONO (4175 4475);
DISPLAY INVISIBLE (4175 4475);
FORCEPROP 0 LAST CDS_SEC 1
J 0
(4175 4475);
DISPLAY 1.021277 (4175 4475);
DISPLAY INVISIBLE (4175 4475);
FORCEPROP 1 LASTPIN (4125 4400) $PN 1
J 0
(4130 4362);
DISPLAY 0.489362 (4130 4362);
PAINT MONO (4130 4362);
FORCEPROP 1 LASTPIN (4125 4200) $PN 2
J 0
(4130 4210);
DISPLAY 0.489362 (4130 4210);
PAINT MONO (4130 4210);
FORCEPROP 1 LAST PACK_TYPE 0402LF
J 0
(4165 4125);
DISPLAY 0.489362 (4165 4125);
PAINT SKYBLUE (4165 4125);
FORCEPROP 1 LAST MATERIAL EMPTY
J 0
(4165 4225);
DISPLAY 0.489362 (4165 4225);
PAINT RED (4165 4225);
FORCEPROP 1 LAST WATTAGE 1/8W
J 0
(4165 4275);
DISPLAY 0.489362 (4165 4275);
PAINT SKYBLUE (4165 4275);
FORCEPROP 1 LAST VALUE 1.5
J 0
(4170 4375);
DISPLAY 0.489362 (4170 4375);
PAINT SKYBLUE (4170 4375);
FORCEPROP 1 LAST TOLERANCE 1%
J 0
(4170 4325);
DISPLAY 0.489362 (4170 4325);
PAINT SKYBLUE (4170 4325);
FORCEPROP 2 LAST CDS_LIB pure_quanta
J 0
(4125 4300);
DISPLAY INVISIBLE (4125 4300);
FORCEPROP 1 LAST PATH I26
J 0
(4175 4475);
DISPLAY 0.978723 (4175 4475);
PAINT WHITE (4175 4475);
DISPLAY INVISIBLE (4175 4475);
FORCEPROP 1 LAST PART_NUMBER CS-1504FB00
J 0
(4165 4175);
DISPLAY 0.489362 (4165 4175);
PAINT SKYBLUE (4165 4175);
DISPLAY INVISIBLE (4165 4175);
FORCEADD UNIVERSAL_GND..1
(650 4325);
FORCEPROP 3 LASTPIN (650 4375) SIG_NAME GND\g
J 0
(660 4385);
DISPLAY 0.659574 (660 4385);
PAINT MONO (660 4385);
DISPLAY INVISIBLE (660 4385);
FORCEPROP 2 LAST CDS_LIB pure_quanta_power
J 0
(650 4325);
PAINT MONO (650 4325);
DISPLAY INVISIBLE (650 4325);
FORCEPROP 1 LAST HDL_POWER GND
J 1
(675 4250);
DISPLAY 0.872340 (675 4250);
PAINT GREEN (675 4250);
DISPLAY INVISIBLE (675 4250);
FORCEPROP 1 LAST PATH I27
J 0
(725 4325);
DISPLAY 0.872340 (725 4325);
PAINT AQUA (725 4325);
DISPLAY INVISIBLE (725 4325);
FORCEADD Q_RES..2
R 2
(650 4550);
FORCEPROP 1 LAST LOCATION PR275
J 2
(605 4675);
DISPLAY 0.489362 (605 4675);
PAINT SKYBLUE (605 4675);
FORCEPROP 0 LAST $SEC 1
J 2
(600 4725);
DISPLAY 0.680851 (600 4725);
PAINT MONO (600 4725);
DISPLAY INVISIBLE (600 4725);
FORCEPROP 0 LAST CDS_SEC 1
J 2
(600 4725);
DISPLAY 1.021277 (600 4725);
DISPLAY INVISIBLE (600 4725);
FORCEPROP 1 LASTPIN (650 4650) $PN 1
J 2
(645 4612);
DISPLAY 0.489362 (645 4612);
PAINT MONO (645 4612);
FORCEPROP 1 LASTPIN (650 4450) $PN 2
J 2
(645 4460);
DISPLAY 0.489362 (645 4460);
PAINT MONO (645 4460);
FORCEPROP 1 LAST VALUE 8.87K
J 2
(595 4625);
DISPLAY 0.489362 (595 4625);
PAINT SKYBLUE (595 4625);
FORCEPROP 1 LAST TOLERANCE 1%
J 2
(595 4575);
DISPLAY 0.489362 (595 4575);
PAINT SKYBLUE (595 4575);
FORCEPROP 1 LAST MATERIAL EMPTY
J 2
(600 4475);
DISPLAY 0.489362 (600 4475);
PAINT RED (600 4475);
FORCEPROP 1 LAST WATTAGE 1/16W
J 2
(600 4525);
DISPLAY 0.489362 (600 4525);
PAINT SKYBLUE (600 4525);
FORCEPROP 1 LAST PACK_TYPE 0402LF
J 2
(600 4375);
DISPLAY 0.489362 (600 4375);
PAINT SKYBLUE (600 4375);
FORCEPROP 2 LAST CDS_LIB pure_quanta
J 2
(650 4550);
DISPLAY INVISIBLE (650 4550);
FORCEPROP 1 LAST PATH I28
J 2
(600 4725);
DISPLAY 0.978723 (600 4725);
PAINT WHITE (600 4725);
DISPLAY INVISIBLE (600 4725);
FORCEPROP 1 LAST PART_NUMBER CS28872FB01
J 2
(600 4425);
DISPLAY 0.489362 (600 4425);
PAINT SKYBLUE (600 4425);
DISPLAY INVISIBLE (600 4425);
FORCEADD OFFPAGE..1
(1125 4400);
FORCEPROP 2 LAST $XR0 217 
J 0
(873 4400);
DISPLAY 0.638298 (873 4400);
PAINT MONO (873 4400);
FORCEPROP 2 LAST CDS_LIB standard
J 0
(1125 4400);
DISPLAY INVISIBLE (1125 4400);
FORCEPROP 1 LAST OFFPAGE TRUE
J 0
(1450 4275);
DISPLAY 0.872340 (1450 4275);
PAINT GREEN (1450 4275);
DISPLAY INVISIBLE (1450 4275);
FORCEPROP 1 LAST COMMENT_BODY TRUE
J 0
(1250 4300);
DISPLAY 0.872340 (1250 4300);
PAINT GREEN (1250 4300);
DISPLAY INVISIBLE (1250 4300);
FORCEPROP 2 LAST PATH I29
J 0
(875 4450);
DISPLAY 0.680851 (875 4450);
DISPLAY INVISIBLE (875 4450);
FORCEADD Q_CAP..1
(100 1875);
FORCEPROP 1 LAST LOCATION PC436_8
J 0
(150 1975);
DISPLAY 0.489362 (150 1975);
PAINT SKYBLUE (150 1975);
FORCEPROP 2 LAST $SEC 1
J 0
(150 2075);
DISPLAY 0.680851 (150 2075);
PAINT MONO (150 2075);
DISPLAY INVISIBLE (150 2075);
FORCEPROP 0 LAST CDS_SEC 1
J 0
(350 1925);
DISPLAY 1.021277 (350 1925);
DISPLAY INVISIBLE (350 1925);
FORCEPROP 1 LASTPIN (100 1975) $PN 1
J 0
(110 1955);
DISPLAY 0.489362 (110 1955);
PAINT MONO (110 1955);
FORCEPROP 1 LASTPIN (100 1775) $PN 2
J 0
(110 1755);
DISPLAY 0.489362 (110 1755);
PAINT MONO (110 1755);
FORCEPROP 1 LAST VALUE 0.1UF
J 0
(150 1925);
DISPLAY 0.489362 (150 1925);
PAINT SKYBLUE (150 1925);
FORCEPROP 1 LAST PACK_TYPE 0402
J 0
(150 1675);
DISPLAY 0.489362 (150 1675);
PAINT SKYBLUE (150 1675);
FORCEPROP 1 LAST MATERIAL X7R
J 0
(150 1775);
DISPLAY 0.489362 (150 1775);
PAINT SKYBLUE (150 1775);
FORCEPROP 1 LAST TOLERANCE 10%
J 0
(150 1825);
DISPLAY 0.489362 (150 1825);
PAINT SKYBLUE (150 1825);
FORCEPROP 1 LAST VOLTAGE 25V
J 0
(150 1875);
DISPLAY 0.489362 (150 1875);
PAINT SKYBLUE (150 1875);
FORCEPROP 2 LAST CDS_LIB pure_quanta
J 0
(100 1875);
DISPLAY INVISIBLE (100 1875);
FORCEPROP 1 LAST PATH I3
J 0
(150 2025);
DISPLAY 0.978723 (150 2025);
PAINT WHITE (150 2025);
DISPLAY INVISIBLE (150 2025);
FORCEPROP 1 LAST PART_NUMBER CH4104K1B00
J 0
(150 1725);
DISPLAY 0.489362 (150 1725);
PAINT SKYBLUE (150 1725);
DISPLAY INVISIBLE (150 1725);
FORCEADD OFFPAGE..5
(1125 4500);
FORCEPROP 2 LAST $XR2 217 
J 0
(870 4536);
DISPLAY 0.638298 (870 4536);
PAINT MONO (870 4536);
FORCEPROP 2 LAST $XR1 223 
J 0
(870 4464);
DISPLAY 0.638298 (870 4464);
PAINT MONO (870 4464);
FORCEPROP 2 LAST $XR0 222 
J 0
(870 4500);
DISPLAY 0.638298 (870 4500);
PAINT MONO (870 4500);
FORCEPROP 2 LAST CDS_LIB standard
J 0
(1125 4500);
DISPLAY INVISIBLE (1125 4500);
FORCEPROP 1 LAST OFFPAGE TRUE
J 0
(1450 4375);
DISPLAY 0.872340 (1450 4375);
PAINT GREEN (1450 4375);
DISPLAY INVISIBLE (1450 4375);
FORCEPROP 1 LAST COMMENT_BODY TRUE
J 0
(1225 4425);
DISPLAY 0.872340 (1225 4425);
PAINT GREEN (1225 4425);
DISPLAY INVISIBLE (1225 4425);
FORCEPROP 2 LAST PATH I30
J 0
(850 4575);
DISPLAY 0.680851 (850 4575);
DISPLAY INVISIBLE (850 4575);
FORCEADD OFFPAGE..5
(1125 5000);
FORCEPROP 2 LAST $XR0 217 
J 0
(870 5000);
DISPLAY 0.638298 (870 5000);
PAINT MONO (870 5000);
FORCEPROP 2 LAST CDS_LIB standard
J 0
(1125 5000);
DISPLAY INVISIBLE (1125 5000);
FORCEPROP 1 LAST OFFPAGE TRUE
J 0
(1450 4875);
DISPLAY 0.872340 (1450 4875);
PAINT GREEN (1450 4875);
DISPLAY INVISIBLE (1450 4875);
FORCEPROP 1 LAST COMMENT_BODY TRUE
J 0
(1225 4925);
DISPLAY 0.872340 (1225 4925);
PAINT GREEN (1225 4925);
DISPLAY INVISIBLE (1225 4925);
FORCEPROP 2 LAST PATH I31
J 0
(850 5050);
DISPLAY 0.680851 (850 5050);
DISPLAY INVISIBLE (850 5050);
FORCEADD OFFPAGE..1
(1125 4900);
FORCEPROP 2 LAST $XR5 223 
J 0
(273 4900);
DISPLAY 0.638298 (273 4900);
PAINT MONO (273 4900);
FORCEPROP 2 LAST $XR4 222 
J 0
(393 4900);
DISPLAY 0.638298 (393 4900);
PAINT MONO (393 4900);
FORCEPROP 2 LAST $XR3 220 
J 0
(513 4900);
DISPLAY 0.638298 (513 4900);
PAINT MONO (513 4900);
FORCEPROP 2 LAST $XR2 219 
J 0
(633 4900);
DISPLAY 0.638298 (633 4900);
PAINT MONO (633 4900);
FORCEPROP 2 LAST $XR1 218 
J 0
(753 4900);
DISPLAY 0.638298 (753 4900);
PAINT MONO (753 4900);
FORCEPROP 2 LAST $XR0 217 
J 0
(873 4900);
DISPLAY 0.638298 (873 4900);
PAINT MONO (873 4900);
FORCEPROP 2 LAST CDS_LIB standard
J 0
(1125 4900);
DISPLAY INVISIBLE (1125 4900);
FORCEPROP 1 LAST OFFPAGE TRUE
J 0
(1450 4775);
DISPLAY 0.872340 (1450 4775);
PAINT GREEN (1450 4775);
DISPLAY INVISIBLE (1450 4775);
FORCEPROP 1 LAST COMMENT_BODY TRUE
J 0
(1250 4800);
DISPLAY 0.872340 (1250 4800);
PAINT GREEN (1250 4800);
DISPLAY INVISIBLE (1250 4800);
FORCEPROP 2 LAST PATH I32
J 0
(875 4950);
DISPLAY 0.680851 (875 4950);
DISPLAY INVISIBLE (875 4950);
FORCEADD UNIVERSAL_GND..1
(1075 5075);
FORCEPROP 3 LASTPIN (1075 5125) SIG_NAME GND\g
J 0
(1085 5135);
DISPLAY 0.659574 (1085 5135);
PAINT MONO (1085 5135);
DISPLAY INVISIBLE (1085 5135);
FORCEPROP 2 LAST CDS_LIB pure_quanta_power
J 0
(1075 5075);
DISPLAY INVISIBLE (1075 5075);
FORCEPROP 1 LAST HDL_POWER GND
J 1
(1100 5000);
DISPLAY 0.872340 (1100 5000);
PAINT GREEN (1100 5000);
DISPLAY INVISIBLE (1100 5000);
FORCEPROP 1 LAST PATH I33
J 0
(1150 5075);
DISPLAY 0.872340 (1150 5075);
PAINT AQUA (1150 5075);
DISPLAY INVISIBLE (1150 5075);
FORCEADD Q_CAP..1
(1075 5275);
FORCEPROP 1 LAST LOCATION PC433
J 0
(1125 5375);
DISPLAY 0.489362 (1125 5375);
PAINT SKYBLUE (1125 5375);
FORCEPROP 0 LAST $SEC 1
J 0
(1125 5425);
DISPLAY 0.680851 (1125 5425);
PAINT MONO (1125 5425);
DISPLAY INVISIBLE (1125 5425);
FORCEPROP 0 LAST CDS_SEC 1
J 0
(1125 5425);
DISPLAY 1.021277 (1125 5425);
DISPLAY INVISIBLE (1125 5425);
FORCEPROP 1 LASTPIN (1075 5375) $PN 1
J 0
(1085 5355);
DISPLAY 0.489362 (1085 5355);
PAINT MONO (1085 5355);
FORCEPROP 1 LASTPIN (1075 5175) $PN 2
J 0
(1085 5155);
DISPLAY 0.489362 (1085 5155);
PAINT MONO (1085 5155);
FORCEPROP 1 LAST PACK_TYPE C0402
J 0
(1125 5075);
DISPLAY 0.489362 (1125 5075);
PAINT SKYBLUE (1125 5075);
FORCEPROP 1 LAST VOLTAGE 10V
J 0
(1125 5275);
DISPLAY 0.489362 (1125 5275);
PAINT SKYBLUE (1125 5275);
FORCEPROP 1 LAST VALUE 2.2UF
J 0
(1125 5325);
DISPLAY 0.489362 (1125 5325);
PAINT SKYBLUE (1125 5325);
FORCEPROP 1 LAST TOLERANCE 10%
J 0
(1125 5225);
DISPLAY 0.489362 (1125 5225);
PAINT SKYBLUE (1125 5225);
FORCEPROP 1 LAST MATERIAL X6S
J 0
(1125 5175);
DISPLAY 0.489362 (1125 5175);
PAINT SKYBLUE (1125 5175);
FORCEPROP 2 LAST CDS_LIB pure_quanta
J 0
(1075 5275);
DISPLAY INVISIBLE (1075 5275);
FORCEPROP 1 LAST PATH I34
J 0
(1125 5425);
DISPLAY 0.978723 (1125 5425);
PAINT WHITE (1125 5425);
DISPLAY INVISIBLE (1125 5425);
FORCEPROP 1 LAST PART_NUMBER CH5222KEB01
J 0
(1125 5125);
DISPLAY 0.489362 (1125 5125);
PAINT SKYBLUE (1125 5125);
DISPLAY INVISIBLE (1125 5125);
FORCEADD Q_RES..2
(1075 5825);
FORCEPROP 1 LAST LOCATION PR277
J 0
(1120 5950);
DISPLAY 0.489362 (1120 5950);
PAINT SKYBLUE (1120 5950);
FORCEPROP 0 LAST $SEC 1
J 0
(1125 6000);
DISPLAY 0.680851 (1125 6000);
PAINT MONO (1125 6000);
DISPLAY INVISIBLE (1125 6000);
FORCEPROP 0 LAST CDS_SEC 1
J 0
(1125 6000);
DISPLAY 1.021277 (1125 6000);
DISPLAY INVISIBLE (1125 6000);
FORCEPROP 1 LASTPIN (1075 5925) $PN 1
J 0
(1080 5887);
DISPLAY 0.489362 (1080 5887);
PAINT MONO (1080 5887);
FORCEPROP 1 LASTPIN (1075 5725) $PN 2
J 0
(1080 5735);
DISPLAY 0.489362 (1080 5735);
PAINT MONO (1080 5735);
FORCEPROP 1 LAST WATTAGE 1/16W
J 0
(1125 5800);
DISPLAY 0.489362 (1125 5800);
PAINT SKYBLUE (1125 5800);
FORCEPROP 1 LAST MATERIAL CHIP
J 0
(1125 5750);
DISPLAY 0.489362 (1125 5750);
PAINT SKYBLUE (1125 5750);
FORCEPROP 1 LAST TOLERANCE 1%
J 0
(1125 5850);
DISPLAY 0.489362 (1125 5850);
PAINT SKYBLUE (1125 5850);
FORCEPROP 1 LAST VALUE 2.2
J 0
(1125 5900);
DISPLAY 0.489362 (1125 5900);
PAINT SKYBLUE (1125 5900);
FORCEPROP 1 LAST PACK_TYPE 0402LF
J 0
(1125 5650);
DISPLAY 0.489362 (1125 5650);
PAINT SKYBLUE (1125 5650);
FORCEPROP 2 LAST CDS_LIB pure_quanta
J 0
(1075 5825);
DISPLAY INVISIBLE (1075 5825);
FORCEPROP 1 LAST PATH I35
J 0
(1125 6000);
DISPLAY 0.978723 (1125 6000);
PAINT WHITE (1125 6000);
DISPLAY INVISIBLE (1125 6000);
FORCEPROP 1 LAST PART_NUMBER CS-2202FB01
J 0
(1125 5700);
DISPLAY 0.489362 (1125 5700);
PAINT SKYBLUE (1125 5700);
DISPLAY INVISIBLE (1125 5700);
FORCEADD VCC_CORE..1
(1075 6225);
FORCEPROP 3 LASTPIN (1075 6175) SIG_NAME PVDDCR_CPU1_P1_PVCC\g
J 0
(1085 6185);
DISPLAY 0.659574 (1085 6185);
PAINT MONO (1085 6185);
DISPLAY INVISIBLE (1085 6185);
FORCEPROP 1 LAST HDL_POWER PVDDCR_CPU1_P1_PVCC
J 1
(1075 6275);
DISPLAY 0.489362 (1075 6275);
PAINT GREEN (1075 6275);
FORCEPROP 2 LAST CDS_LIB pure_quanta_power
J 0
(1075 6225);
DISPLAY INVISIBLE (1075 6225);
FORCEPROP 1 LAST PATH I36
J 0
(1125 6250);
DISPLAY 0.872340 (1125 6250);
PAINT AQUA (1125 6250);
DISPLAY INVISIBLE (1125 6250);
FORCEADD UNIVERSAL_GND..1
(1425 5575);
FORCEPROP 3 LASTPIN (1425 5625) SIG_NAME GND\g
J 0
(1435 5635);
DISPLAY 0.659574 (1435 5635);
PAINT MONO (1435 5635);
DISPLAY INVISIBLE (1435 5635);
FORCEPROP 2 LAST CDS_LIB pure_quanta_power
J 0
(1425 5575);
DISPLAY INVISIBLE (1425 5575);
FORCEPROP 1 LAST HDL_POWER GND
J 1
(1450 5500);
DISPLAY 0.872340 (1450 5500);
PAINT GREEN (1450 5500);
DISPLAY INVISIBLE (1450 5500);
FORCEPROP 1 LAST PATH I37
J 0
(1500 5575);
DISPLAY 0.872340 (1500 5575);
PAINT AQUA (1500 5575);
DISPLAY INVISIBLE (1500 5575);
FORCEADD Q_CAP..1
(1425 5850);
FORCEPROP 1 LAST LOCATION PC437_IOP1_1
J 0
(1475 5950);
DISPLAY 0.489362 (1475 5950);
PAINT SKYBLUE (1475 5950);
FORCEPROP 0 LAST $SEC 1
J 0
(1475 6000);
DISPLAY 0.680851 (1475 6000);
PAINT MONO (1475 6000);
DISPLAY INVISIBLE (1475 6000);
FORCEPROP 0 LAST CDS_SEC 1
J 0
(1475 6000);
DISPLAY 1.021277 (1475 6000);
DISPLAY INVISIBLE (1475 6000);
FORCEPROP 1 LASTPIN (1425 5950) $PN 1
J 0
(1435 5930);
DISPLAY 0.489362 (1435 5930);
PAINT MONO (1435 5930);
FORCEPROP 1 LASTPIN (1425 5750) $PN 2
J 0
(1435 5730);
DISPLAY 0.489362 (1435 5730);
PAINT MONO (1435 5730);
FORCEPROP 1 LAST PACK_TYPE C0402
J 0
(1475 5650);
DISPLAY 0.489362 (1475 5650);
PAINT SKYBLUE (1475 5650);
FORCEPROP 1 LAST VOLTAGE 10V
J 0
(1475 5850);
DISPLAY 0.489362 (1475 5850);
PAINT SKYBLUE (1475 5850);
FORCEPROP 1 LAST VALUE 2.2UF
J 0
(1475 5900);
DISPLAY 0.489362 (1475 5900);
PAINT SKYBLUE (1475 5900);
FORCEPROP 1 LAST TOLERANCE 10%
J 0
(1475 5800);
DISPLAY 0.489362 (1475 5800);
PAINT SKYBLUE (1475 5800);
FORCEPROP 1 LAST MATERIAL X6S
J 0
(1475 5750);
DISPLAY 0.489362 (1475 5750);
PAINT SKYBLUE (1475 5750);
FORCEPROP 2 LAST CDS_LIB pure_quanta
J 0
(1425 5850);
DISPLAY INVISIBLE (1425 5850);
FORCEPROP 1 LAST PATH I38
J 0
(1475 6000);
DISPLAY 0.978723 (1475 6000);
PAINT WHITE (1475 6000);
DISPLAY INVISIBLE (1475 6000);
FORCEPROP 1 LAST PART_NUMBER CH5222KEB01
J 0
(1475 5700);
DISPLAY 0.489362 (1475 5700);
PAINT SKYBLUE (1475 5700);
DISPLAY INVISIBLE (1475 5700);
FORCEADD ISL99390FRZTR5935..1
(2650 5000);
FORCEPROP 1 LAST LOCATION PU39
J 0
(2350 5875);
DISPLAY 0.489362 (2350 5875);
PAINT SKYBLUE (2350 5875);
FORCEPROP 2 LAST $SEC 1
J 0
(2350 5925);
DISPLAY 0.680851 (2350 5925);
PAINT MONO (2350 5925);
DISPLAY INVISIBLE (2350 5925);
FORCEPROP 2 LAST CDS_SEC 1
J 0
(2400 6000);
DISPLAY 1.021277 (2400 6000);
DISPLAY INVISIBLE (2400 6000);
FORCEPROP 2 LASTPIN (3050 4550) $PN 2
J 0
(3060 4560);
DISPLAY 0.489362 (3060 4560);
PAINT MONO (3060 4560);
FORCEPROP 2 LASTPIN (3050 5350) $PN 33
J 0
(3060 5360);
DISPLAY 0.489362 (3060 5360);
PAINT MONO (3060 5360);
FORCEPROP 2 LASTPIN (2200 4750) $PN 31
J 2
(2190 4760);
DISPLAY 0.489362 (2190 4760);
PAINT MONO (2190 4760);
FORCEPROP 2 LASTPIN (2200 5150) $PN 35
J 2
(2190 5160);
DISPLAY 0.489362 (2190 5160);
PAINT MONO (2190 5160);
FORCEPROP 2 LASTPIN (3050 4700) $PN 6
J 0
(3060 4710);
DISPLAY 0.489362 (3060 4710);
PAINT MONO (3060 4710);
FORCEPROP 2 LASTPIN (3050 4650) $PN 41
J 0
(3060 4660);
DISPLAY 0.489362 (3060 4660);
PAINT MONO (3060 4660);
FORCEPROP 2 LASTPIN (2200 5000) $PN 38
J 2
(2190 5010);
DISPLAY 0.489362 (2190 5010);
PAINT MONO (2190 5010);
FORCEPROP 2 LASTPIN (2200 4700) $PN 37
J 2
(2190 4710);
DISPLAY 0.489362 (2190 4710);
PAINT MONO (2190 4710);
FORCEPROP 2 LASTPIN (3050 4500) $PN 5
J 0
(3060 4510);
DISPLAY 0.489362 (3060 4510);
PAINT MONO (3060 4510);
FORCEPROP 2 LASTPIN (3050 4450) $PN 7_9-20_24
J 0
(3060 4460);
DISPLAY 0.489362 (3060 4460);
PAINT MONO (3060 4460);
FORCEPROP 2 LASTPIN (3050 4400) $PN 40
J 0
(3060 4410);
DISPLAY 0.489362 (3060 4410);
PAINT MONO (3060 4410);
FORCEPROP 2 LASTPIN (3050 5100) $PN 32
J 0
(3060 5110);
DISPLAY 0.489362 (3060 5110);
PAINT MONO (3060 5110);
FORCEPROP 2 LASTPIN (2200 5650) $PN 4
J 2
(2190 5660);
DISPLAY 0.489362 (2190 5660);
PAINT MONO (2190 5660);
FORCEPROP 2 LASTPIN (2200 4400) $PN 34
J 2
(2190 4410);
DISPLAY 0.489362 (2190 4410);
PAINT MONO (2190 4410);
FORCEPROP 2 LASTPIN (2200 4900) $PN 39
J 2
(2190 4910);
DISPLAY 0.489362 (2190 4910);
PAINT MONO (2190 4910);
FORCEPROP 2 LASTPIN (3050 5000) $PN 10_19
J 0
(3060 5010);
DISPLAY 0.489362 (3060 5010);
PAINT MONO (3060 5010);
FORCEPROP 2 LASTPIN (2200 4500) $PN 36
J 2
(2190 4510);
DISPLAY 0.489362 (2190 4510);
PAINT MONO (2190 4510);
FORCEPROP 2 LASTPIN (2200 5350) $PN 3
J 2
(2190 5360);
DISPLAY 0.489362 (2190 5360);
PAINT MONO (2190 5360);
FORCEPROP 2 LASTPIN (3050 5650) $PN 25_29
J 0
(3060 5660);
DISPLAY 0.489362 (3060 5660);
PAINT MONO (3060 5660);
FORCEPROP 2 LASTPIN (3050 5600) $PN 30
J 0
(3060 5610);
DISPLAY 0.489362 (3060 5610);
PAINT MONO (3060 5610);
FORCEPROP 2 LASTPIN (3050 4750) $PN 1
J 0
(3060 4760);
DISPLAY 0.489362 (3060 4760);
PAINT MONO (3060 4760);
FORCEPROP 2 LAST VALUE ISL99390FRZ-TR5935
J 0
(2350 5975);
DISPLAY 0.489362 (2350 5975);
PAINT SKYBLUE (2350 5975);
FORCEPROP 1 LAST MATERIAL IC
J 0
(2350 5725);
DISPLAY 0.489362 (2350 5725);
PAINT SKYBLUE (2350 5725);
FORCEPROP 2 LAST PART_TYPE SMLF
J 0
(2350 6025);
DISPLAY 0.638298 (2350 6025);
FORCEPROP 2 LAST CDS_LIB pure_quanta
J 0
(2650 5000);
DISPLAY INVISIBLE (2650 5000);
FORCEPROP 1 LAST CDS_LMAN_SYM_OUTLINE -300,700,250,-650
J 0
(2650 5000);
DISPLAY 0.468085 (2650 5000);
PAINT GREEN (2650 5000);
DISPLAY INVISIBLE (2650 5000);
FORCEPROP 1 LAST NEEDS_NO_SIZE TRUE
J 0
(2650 5000);
DISPLAY 0.723404 (2650 5000);
PAINT GREEN (2650 5000);
DISPLAY INVISIBLE (2650 5000);
FORCEPROP 1 LAST PATH I39
J 0
(2650 5000);
DISPLAY 0.723404 (2650 5000);
PAINT GREEN (2650 5000);
DISPLAY INVISIBLE (2650 5000);
FORCEPROP 1 LAST PART_NUMBER AL099390004
J 0
(2350 5800);
DISPLAY 0.489362 (2350 5800);
PAINT SKYBLUE (2350 5800);
DISPLAY INVISIBLE (2350 5800);
FORCEADD Q_CAP..1
(100 4625);
FORCEPROP 1 LAST LOCATION PC435_7
J 0
(150 4725);
DISPLAY 0.489362 (150 4725);
PAINT SKYBLUE (150 4725);
FORCEPROP 2 LAST $SEC 1
J 0
(150 4825);
DISPLAY 0.680851 (150 4825);
PAINT MONO (150 4825);
DISPLAY INVISIBLE (150 4825);
FORCEPROP 0 LAST CDS_SEC 1
J 0
(350 4675);
DISPLAY 1.021277 (350 4675);
DISPLAY INVISIBLE (350 4675);
FORCEPROP 1 LASTPIN (100 4725) $PN 1
J 0
(110 4705);
DISPLAY 0.489362 (110 4705);
PAINT MONO (110 4705);
FORCEPROP 1 LASTPIN (100 4525) $PN 2
J 0
(110 4505);
DISPLAY 0.489362 (110 4505);
PAINT MONO (110 4505);
FORCEPROP 1 LAST PACK_TYPE 0402
J 0
(150 4425);
DISPLAY 0.489362 (150 4425);
PAINT SKYBLUE (150 4425);
FORCEPROP 1 LAST VOLTAGE 25V
J 0
(150 4625);
DISPLAY 0.489362 (150 4625);
PAINT SKYBLUE (150 4625);
FORCEPROP 1 LAST VALUE 0.1UF
J 0
(150 4675);
DISPLAY 0.489362 (150 4675);
PAINT SKYBLUE (150 4675);
FORCEPROP 1 LAST MATERIAL X7R
J 0
(150 4525);
DISPLAY 0.489362 (150 4525);
PAINT SKYBLUE (150 4525);
FORCEPROP 1 LAST TOLERANCE 10%
J 0
(150 4575);
DISPLAY 0.489362 (150 4575);
PAINT SKYBLUE (150 4575);
FORCEPROP 2 LAST CDS_LIB pure_quanta
J 0
(100 4625);
DISPLAY INVISIBLE (100 4625);
FORCEPROP 1 LAST PATH I4
J 0
(150 4775);
DISPLAY 0.978723 (150 4775);
PAINT WHITE (150 4775);
DISPLAY INVISIBLE (150 4775);
FORCEPROP 1 LAST PART_NUMBER CH4104K1B00
J 0
(150 4475);
DISPLAY 0.489362 (150 4475);
PAINT SKYBLUE (150 4475);
DISPLAY INVISIBLE (150 4475);
FORCEADD Q_CAP..1
(4125 4800);
FORCEPROP 1 LAST LOCATION PC174
J 0
(4175 4900);
DISPLAY 0.489362 (4175 4900);
PAINT SKYBLUE (4175 4900);
FORCEPROP 0 LAST $SEC 1
J 0
(4175 4950);
DISPLAY 0.680851 (4175 4950);
PAINT MONO (4175 4950);
DISPLAY INVISIBLE (4175 4950);
FORCEPROP 0 LAST CDS_SEC 1
J 0
(4175 4950);
DISPLAY 1.021277 (4175 4950);
DISPLAY INVISIBLE (4175 4950);
FORCEPROP 1 LASTPIN (4125 4900) $PN 1
J 0
(4135 4880);
DISPLAY 0.489362 (4135 4880);
PAINT MONO (4135 4880);
FORCEPROP 1 LASTPIN (4125 4700) $PN 2
J 0
(4135 4680);
DISPLAY 0.489362 (4135 4680);
PAINT MONO (4135 4680);
FORCEPROP 1 LAST PACK_TYPE C0402
J 0
(4175 4600);
DISPLAY 0.489362 (4175 4600);
PAINT SKYBLUE (4175 4600);
FORCEPROP 1 LAST TOLERANCE 10%
J 0
(4175 4750);
DISPLAY 0.489362 (4175 4750);
PAINT SKYBLUE (4175 4750);
FORCEPROP 1 LAST VOLTAGE 50V
J 0
(4175 4800);
DISPLAY 0.489362 (4175 4800);
PAINT SKYBLUE (4175 4800);
FORCEPROP 1 LAST VALUE 560PF
J 0
(4175 4850);
DISPLAY 0.489362 (4175 4850);
PAINT SKYBLUE (4175 4850);
FORCEPROP 1 LAST MATERIAL EMPTY
J 0
(4175 4700);
DISPLAY 0.489362 (4175 4700);
PAINT RED (4175 4700);
FORCEPROP 2 LAST CDS_LIB pure_quanta
J 0
(4125 4800);
DISPLAY INVISIBLE (4125 4800);
FORCEPROP 1 LAST PATH I40
J 0
(4175 4950);
DISPLAY 0.978723 (4175 4950);
PAINT WHITE (4175 4950);
DISPLAY INVISIBLE (4175 4950);
FORCEPROP 1 LAST PART_NUMBER CH1566K1B09
J 0
(4175 4650);
DISPLAY 0.489362 (4175 4650);
PAINT SKYBLUE (4175 4650);
DISPLAY INVISIBLE (4175 4650);
FORCEADD Q_CAP..1
(3325 5925);
FORCEPROP 1 LAST LOCATION PC438_1
J 0
(3375 6075);
DISPLAY 0.489362 (3375 6075);
PAINT SKYBLUE (3375 6075);
FORCEPROP 0 LAST $SEC 1
J 0
(3375 6075);
DISPLAY 0.680851 (3375 6075);
PAINT MONO (3375 6075);
DISPLAY INVISIBLE (3375 6075);
FORCEPROP 0 LAST CDS_SEC 1
J 0
(3375 6075);
DISPLAY 1.021277 (3375 6075);
DISPLAY INVISIBLE (3375 6075);
FORCEPROP 1 LASTPIN (3325 6025) $PN 1
J 0
(3335 6005);
DISPLAY 0.489362 (3335 6005);
PAINT MONO (3335 6005);
FORCEPROP 1 LASTPIN (3325 5825) $PN 2
J 0
(3335 5805);
DISPLAY 0.489362 (3335 5805);
PAINT MONO (3335 5805);
FORCEPROP 1 LAST PACK_TYPE 0402
J 0
(3375 5775);
DISPLAY 0.489362 (3375 5775);
PAINT SKYBLUE (3375 5775);
FORCEPROP 1 LAST VOLTAGE 25V
J 0
(3375 5975);
DISPLAY 0.489362 (3375 5975);
PAINT SKYBLUE (3375 5975);
FORCEPROP 1 LAST VALUE 0.1UF
J 0
(3375 6025);
DISPLAY 0.489362 (3375 6025);
PAINT SKYBLUE (3375 6025);
FORCEPROP 1 LAST MATERIAL X7R
J 0
(3375 5875);
DISPLAY 0.489362 (3375 5875);
PAINT SKYBLUE (3375 5875);
FORCEPROP 1 LAST TOLERANCE 10%
J 0
(3375 5925);
DISPLAY 0.489362 (3375 5925);
PAINT SKYBLUE (3375 5925);
FORCEPROP 2 LAST CDS_LIB pure_quanta
J 0
(3325 5925);
DISPLAY INVISIBLE (3325 5925);
FORCEPROP 1 LAST PATH I41
J 0
(3375 6075);
DISPLAY 0.978723 (3375 6075);
PAINT WHITE (3375 6075);
DISPLAY INVISIBLE (3375 6075);
FORCEPROP 1 LAST PART_NUMBER CH4104K1B00
J 0
(3375 5825);
DISPLAY 0.489362 (3375 5825);
PAINT SKYBLUE (3375 5825);
DISPLAY INVISIBLE (3375 5825);
FORCEADD Q_CAP..1
(3675 5900);
FORCEPROP 1 LAST LOCATION PC440_1
J 0
(3725 6050);
DISPLAY 0.489362 (3725 6050);
PAINT SKYBLUE (3725 6050);
FORCEPROP 0 LAST $SEC 1
J 0
(3725 6100);
DISPLAY 0.680851 (3725 6100);
PAINT MONO (3725 6100);
DISPLAY INVISIBLE (3725 6100);
FORCEPROP 0 LAST CDS_SEC 1
J 0
(3725 6100);
DISPLAY 1.021277 (3725 6100);
DISPLAY INVISIBLE (3725 6100);
FORCEPROP 1 LASTPIN (3675 6000) $PN 1
J 0
(3685 5980);
DISPLAY 0.489362 (3685 5980);
PAINT MONO (3685 5980);
FORCEPROP 1 LASTPIN (3675 5800) $PN 2
J 0
(3685 5780);
DISPLAY 0.489362 (3685 5780);
PAINT MONO (3685 5780);
FORCEPROP 1 LAST VALUE 1UF
J 0
(3725 6000);
DISPLAY 0.489362 (3725 6000);
PAINT SKYBLUE (3725 6000);
FORCEPROP 1 LAST VOLTAGE 25V
J 0
(3725 5950);
DISPLAY 0.489362 (3725 5950);
PAINT SKYBLUE (3725 5950);
FORCEPROP 1 LAST TOLERANCE 10%
J 0
(3725 5900);
DISPLAY 0.489362 (3725 5900);
PAINT SKYBLUE (3725 5900);
FORCEPROP 1 LAST PACK_TYPE C0402
J 0
(3725 5800);
DISPLAY 0.489362 (3725 5800);
PAINT SKYBLUE (3725 5800);
FORCEPROP 1 LAST MATERIAL X6S
J 0
(3725 5850);
DISPLAY 0.489362 (3725 5850);
PAINT SKYBLUE (3725 5850);
FORCEPROP 2 LAST CDS_LIB pure_quanta
J 0
(3675 5900);
DISPLAY INVISIBLE (3675 5900);
FORCEPROP 1 LAST PATH I42
J 0
(3725 6050);
DISPLAY 0.978723 (3725 6050);
PAINT WHITE (3725 6050);
DISPLAY INVISIBLE (3725 6050);
FORCEPROP 1 LAST PART_NUMBER CH5104KEB02
J 0
(3725 5750);
DISPLAY 0.489362 (3725 5750);
PAINT SKYBLUE (3725 5750);
DISPLAY INVISIBLE (3725 5750);
FORCEADD Q_RES..1
(3975 5350);
FORCEPROP 1 LAST LOCATION PR279
J 0
(3925 5400);
DISPLAY 0.489362 (3925 5400);
PAINT SKYBLUE (3925 5400);
FORCEPROP 2 LAST $SEC 1
J 0
(3925 5550);
DISPLAY 0.680851 (3925 5550);
PAINT MONO (3925 5550);
DISPLAY INVISIBLE (3925 5550);
FORCEPROP 2 LAST CDS_SEC 1
J 0
(3925 5550);
DISPLAY 1.021277 (3925 5550);
DISPLAY INVISIBLE (3925 5550);
FORCEPROP 1 LASTPIN (3875 5350) $PN 1
J 0
(3887 5362);
DISPLAY 0.489362 (3887 5362);
FORCEPROP 1 LASTPIN (4075 5350) $PN 2
J 0
(4037 5362);
DISPLAY 0.489362 (4037 5362);
FORCEPROP 1 LAST VALUE 5.6
J 2
(3850 5375);
DISPLAY 0.489362 (3850 5375);
PAINT SKYBLUE (3850 5375);
FORCEPROP 1 LAST WATTAGE 1/16W
J 2
(4200 5375);
DISPLAY 0.489362 (4200 5375);
PAINT SKYBLUE (4200 5375);
FORCEPROP 1 LAST MATERIAL CHIP
J 0
(4075 5300);
DISPLAY 0.489362 (4075 5300);
PAINT SKYBLUE (4075 5300);
FORCEPROP 1 LAST TOLERANCE 1%
J 0
(3825 5250);
DISPLAY 0.489362 (3825 5250);
PAINT SKYBLUE (3825 5250);
FORCEPROP 1 LAST PACK_TYPE 0402LF
J 0
(4050 5250);
DISPLAY 0.489362 (4050 5250);
PAINT SKYBLUE (4050 5250);
FORCEPROP 2 LAST CDS_LIB pure_quanta
J 0
(3975 5350);
PAINT MONO (3975 5350);
DISPLAY INVISIBLE (3975 5350);
FORCEPROP 1 LAST PATH I43
J 0
(3925 5500);
DISPLAY 0.978723 (3925 5500);
PAINT WHITE (3925 5500);
DISPLAY INVISIBLE (3925 5500);
FORCEPROP 1 LAST PART_NUMBER CS-5602FB01
J 0
(3700 5300);
DISPLAY 0.489362 (3700 5300);
PAINT SKYBLUE (3700 5300);
DISPLAY INVISIBLE (3700 5300);
FORCEADD Q_CAP..1
(4000 5900);
FORCEPROP 1 LAST LOCATION PC442_1
J 0
(4050 6050);
DISPLAY 0.489362 (4050 6050);
PAINT SKYBLUE (4050 6050);
FORCEPROP 0 LAST $SEC 1
J 0
(4050 6100);
DISPLAY 0.680851 (4050 6100);
PAINT MONO (4050 6100);
DISPLAY INVISIBLE (4050 6100);
FORCEPROP 0 LAST CDS_SEC 1
J 0
(4050 6100);
DISPLAY 1.021277 (4050 6100);
DISPLAY INVISIBLE (4050 6100);
FORCEPROP 1 LASTPIN (4000 6000) $PN 1
J 0
(4010 5980);
DISPLAY 0.489362 (4010 5980);
PAINT MONO (4010 5980);
FORCEPROP 1 LASTPIN (4000 5800) $PN 2
J 0
(4010 5780);
DISPLAY 0.489362 (4010 5780);
PAINT MONO (4010 5780);
FORCEPROP 1 LAST MATERIAL X6S
J 0
(4050 5850);
DISPLAY 0.489362 (4050 5850);
PAINT SKYBLUE (4050 5850);
FORCEPROP 1 LAST VOLTAGE 16V
J 0
(4050 5950);
DISPLAY 0.489362 (4050 5950);
PAINT SKYBLUE (4050 5950);
FORCEPROP 1 LAST TOLERANCE 20%
J 0
(4050 5900);
DISPLAY 0.489362 (4050 5900);
PAINT SKYBLUE (4050 5900);
FORCEPROP 1 LAST VALUE 22UF
J 0
(4050 6000);
DISPLAY 0.489362 (4050 6000);
PAINT SKYBLUE (4050 6000);
FORCEPROP 1 LAST PACK_TYPE C0805
J 0
(4050 5800);
DISPLAY 0.489362 (4050 5800);
PAINT SKYBLUE (4050 5800);
FORCEPROP 2 LAST CDS_LIB pure_quanta
J 0
(4000 5900);
DISPLAY INVISIBLE (4000 5900);
FORCEPROP 1 LAST PATH I44
J 0
(4050 6050);
DISPLAY 0.978723 (4050 6050);
PAINT WHITE (4050 6050);
DISPLAY INVISIBLE (4050 6050);
FORCEPROP 1 LAST PART_NUMBER CH6223MEA01
J 0
(4050 5750);
DISPLAY 0.382979 (4050 5750);
PAINT SKYBLUE (4050 5750);
DISPLAY INVISIBLE (4050 5750);
FORCEADD Q_RES..1
(5000 1225);
FORCEPROP 1 LAST LOCATION PR281
J 0
(4950 1250);
DISPLAY 0.489362 (4950 1250);
PAINT SKYBLUE (4950 1250);
FORCEPROP 0 LAST $SEC 1
J 0
(5250 1350);
DISPLAY 0.680851 (5250 1350);
PAINT MONO (5250 1350);
DISPLAY INVISIBLE (5250 1350);
FORCEPROP 0 LAST CDS_SEC 1
J 0
(5250 1350);
DISPLAY 1.021277 (5250 1350);
DISPLAY INVISIBLE (5250 1350);
FORCEPROP 1 LASTPIN (4900 1225) $PN 1
J 0
(4912 1237);
DISPLAY 0.787234 (4912 1237);
PAINT MONO (4912 1237);
DISPLAY INVISIBLE (4912 1237);
FORCEPROP 1 LASTPIN (5100 1225) $PN 2
J 0
(5062 1237);
DISPLAY 0.787234 (5062 1237);
PAINT MONO (5062 1237);
DISPLAY INVISIBLE (5062 1237);
FORCEPROP 1 LAST WATTAGE 1/16W
J 2
(5225 1300);
DISPLAY 0.489362 (5225 1300);
PAINT SKYBLUE (5225 1300);
FORCEPROP 1 LAST MATERIAL CHIP
J 0
(5125 1250);
DISPLAY 0.489362 (5125 1250);
PAINT SKYBLUE (5125 1250);
FORCEPROP 1 LAST TOLERANCE 5%
J 0
(4825 1275);
DISPLAY 0.489362 (4825 1275);
PAINT SKYBLUE (4825 1275);
FORCEPROP 1 LAST VALUE 0
J 2
(4800 1275);
DISPLAY 0.489362 (4800 1275);
PAINT SKYBLUE (4800 1275);
FORCEPROP 1 LAST PACK_TYPE 0402LF
J 0
(5100 1175);
DISPLAY 0.489362 (5100 1175);
PAINT SKYBLUE (5100 1175);
FORCEPROP 2 LAST CDS_LIB pure_quanta
J 0
(5000 1225);
DISPLAY INVISIBLE (5000 1225);
FORCEPROP 1 LAST PATH I45
J 0
(4950 1375);
DISPLAY 0.978723 (4950 1375);
PAINT WHITE (4950 1375);
DISPLAY INVISIBLE (4950 1375);
FORCEPROP 1 LAST PART_NUMBER CS00002JB13
J 0
(4700 1175);
DISPLAY 0.489362 (4700 1175);
PAINT SKYBLUE (4700 1175);
DISPLAY INVISIBLE (4700 1175);
FORCEADD OFFPAGE..6
(5075 2000);
FORCEPROP 2 LAST $XR0 223 
J 0
(4795 2000);
DISPLAY 0.638298 (4795 2000);
PAINT MONO (4795 2000);
FORCEPROP 2 LAST CDS_LIB standard
J 0
(5075 2000);
DISPLAY INVISIBLE (5075 2000);
FORCEPROP 1 LAST OFFPAGE TRUE
J 0
(5400 1875);
DISPLAY 0.872340 (5400 1875);
PAINT GREEN (5400 1875);
DISPLAY INVISIBLE (5400 1875);
FORCEPROP 1 LAST COMMENT_BODY TRUE
J 0
(5175 1925);
DISPLAY 0.872340 (5175 1925);
PAINT GREEN (5175 1925);
DISPLAY INVISIBLE (5175 1925);
FORCEPROP 2 LAST PATH I46
J 0
(4775 2050);
DISPLAY 0.680851 (4775 2050);
DISPLAY INVISIBLE (4775 2050);
FORCEADD Q_CAP..1
(4650 2475);
FORCEPROP 1 LAST LOCATION PC445
J 0
(4700 2575);
DISPLAY 0.489362 (4700 2575);
PAINT SKYBLUE (4700 2575);
FORCEPROP 0 LAST $SEC 1
J 0
(4700 2625);
DISPLAY 0.680851 (4700 2625);
PAINT MONO (4700 2625);
DISPLAY INVISIBLE (4700 2625);
FORCEPROP 0 LAST CDS_SEC 1
J 2
(4700 2600);
DISPLAY 1.021277 (4700 2600);
DISPLAY INVISIBLE (4700 2600);
FORCEPROP 1 LASTPIN (4650 2575) $PN 1
J 0
(4660 2555);
DISPLAY 0.489362 (4660 2555);
PAINT MONO (4660 2555);
FORCEPROP 1 LASTPIN (4650 2375) $PN 2
J 0
(4660 2355);
DISPLAY 0.489362 (4660 2355);
PAINT MONO (4660 2355);
FORCEPROP 1 LAST PACK_TYPE 0402
J 0
(4700 2275);
DISPLAY 0.489362 (4700 2275);
PAINT SKYBLUE (4700 2275);
FORCEPROP 1 LAST VOLTAGE 16V
J 0
(4700 2475);
DISPLAY 0.489362 (4700 2475);
PAINT SKYBLUE (4700 2475);
FORCEPROP 1 LAST VALUE 0.22UF
J 0
(4700 2525);
DISPLAY 0.489362 (4700 2525);
PAINT SKYBLUE (4700 2525);
FORCEPROP 1 LAST TOLERANCE 10%
J 0
(4700 2425);
DISPLAY 0.489362 (4700 2425);
PAINT SKYBLUE (4700 2425);
FORCEPROP 1 LAST MATERIAL X7R
J 0
(4700 2375);
DISPLAY 0.489362 (4700 2375);
PAINT SKYBLUE (4700 2375);
FORCEPROP 2 LAST CDS_LIB pure_quanta
J 2
(4650 2475);
DISPLAY INVISIBLE (4650 2475);
FORCEPROP 1 LAST PATH I47
J 0
(4700 2625);
DISPLAY 0.978723 (4700 2625);
PAINT WHITE (4700 2625);
DISPLAY INVISIBLE (4700 2625);
FORCEPROP 1 LAST PART_NUMBER CH4223K1B00
J 0
(4700 2325);
DISPLAY 0.489362 (4700 2325);
PAINT SKYBLUE (4700 2325);
DISPLAY INVISIBLE (4700 2325);
FORCEADD Q_CAP..1
(4375 3175);
FORCEPROP 1 LAST LOCATION PC443_2
J 0
(4425 3325);
DISPLAY 0.489362 (4425 3325);
PAINT SKYBLUE (4425 3325);
FORCEPROP 0 LAST $SEC 1
J 0
(4425 3375);
DISPLAY 0.680851 (4425 3375);
PAINT MONO (4425 3375);
DISPLAY INVISIBLE (4425 3375);
FORCEPROP 0 LAST CDS_SEC 1
J 0
(4425 3375);
DISPLAY 1.021277 (4425 3375);
DISPLAY INVISIBLE (4425 3375);
FORCEPROP 1 LASTPIN (4375 3275) $PN 1
J 0
(4385 3255);
DISPLAY 0.489362 (4385 3255);
PAINT MONO (4385 3255);
FORCEPROP 1 LASTPIN (4375 3075) $PN 2
J 0
(4385 3055);
DISPLAY 0.489362 (4385 3055);
PAINT MONO (4385 3055);
FORCEPROP 1 LAST MATERIAL X6S
J 0
(4425 3125);
DISPLAY 0.489362 (4425 3125);
PAINT SKYBLUE (4425 3125);
FORCEPROP 1 LAST VALUE 22UF
J 0
(4425 3275);
DISPLAY 0.489362 (4425 3275);
PAINT SKYBLUE (4425 3275);
FORCEPROP 1 LAST VOLTAGE 16V
J 0
(4425 3225);
DISPLAY 0.489362 (4425 3225);
PAINT SKYBLUE (4425 3225);
FORCEPROP 1 LAST TOLERANCE 20%
J 0
(4425 3175);
DISPLAY 0.489362 (4425 3175);
PAINT SKYBLUE (4425 3175);
FORCEPROP 1 LAST PACK_TYPE C0805
J 0
(4425 3075);
DISPLAY 0.489362 (4425 3075);
PAINT SKYBLUE (4425 3075);
FORCEPROP 2 LAST CDS_LIB pure_quanta
J 0
(4375 3175);
DISPLAY INVISIBLE (4375 3175);
FORCEPROP 1 LAST PATH I48
J 0
(4425 3325);
DISPLAY 0.978723 (4425 3325);
PAINT WHITE (4425 3325);
DISPLAY INVISIBLE (4425 3325);
FORCEPROP 1 LAST PART_NUMBER CH6223MEA01
J 0
(4425 3025);
DISPLAY 0.489362 (4425 3025);
PAINT SKYBLUE (4425 3025);
DISPLAY INVISIBLE (4425 3025);
FORCEADD Q_CAP..1
(4775 3175);
FORCEPROP 1 LAST LOCATION PC446_2
J 0
(4825 3325);
DISPLAY 0.489362 (4825 3325);
PAINT SKYBLUE (4825 3325);
FORCEPROP 0 LAST $SEC 1
J 0
(4825 3375);
DISPLAY 0.680851 (4825 3375);
PAINT MONO (4825 3375);
DISPLAY INVISIBLE (4825 3375);
FORCEPROP 0 LAST CDS_SEC 1
J 0
(4825 3375);
DISPLAY 1.021277 (4825 3375);
DISPLAY INVISIBLE (4825 3375);
FORCEPROP 1 LASTPIN (4775 3275) $PN 1
J 0
(4785 3255);
DISPLAY 0.489362 (4785 3255);
PAINT MONO (4785 3255);
FORCEPROP 1 LASTPIN (4775 3075) $PN 2
J 0
(4785 3055);
DISPLAY 0.489362 (4785 3055);
PAINT MONO (4785 3055);
FORCEPROP 1 LAST MATERIAL X6S
J 0
(4825 3125);
DISPLAY 0.489362 (4825 3125);
PAINT SKYBLUE (4825 3125);
FORCEPROP 1 LAST PACK_TYPE C0805
J 0
(4825 3075);
DISPLAY 0.489362 (4825 3075);
PAINT SKYBLUE (4825 3075);
FORCEPROP 1 LAST VALUE 22UF
J 0
(4825 3275);
DISPLAY 0.489362 (4825 3275);
PAINT SKYBLUE (4825 3275);
FORCEPROP 1 LAST VOLTAGE 16V
J 0
(4825 3225);
DISPLAY 0.489362 (4825 3225);
PAINT SKYBLUE (4825 3225);
FORCEPROP 1 LAST TOLERANCE 20%
J 0
(4825 3175);
DISPLAY 0.489362 (4825 3175);
PAINT SKYBLUE (4825 3175);
FORCEPROP 2 LAST CDS_LIB pure_quanta
J 0
(4775 3175);
DISPLAY INVISIBLE (4775 3175);
FORCEPROP 1 LAST PATH I49
J 0
(4825 3325);
DISPLAY 0.978723 (4825 3325);
PAINT WHITE (4825 3325);
DISPLAY INVISIBLE (4825 3325);
FORCEPROP 1 LAST PART_NUMBER CH6223MEA01
J 0
(4825 3025);
DISPLAY 0.489362 (4825 3025);
PAINT SKYBLUE (4825 3025);
DISPLAY INVISIBLE (4825 3025);
FORCEADD UNIVERSAL_GND..1
(625 1525);
FORCEPROP 3 LASTPIN (625 1575) SIG_NAME GND\g
J 0
(635 1585);
DISPLAY 0.659574 (635 1585);
PAINT MONO (635 1585);
DISPLAY INVISIBLE (635 1585);
FORCEPROP 2 LAST CDS_LIB pure_quanta_power
J 0
(625 1525);
PAINT MONO (625 1525);
DISPLAY INVISIBLE (625 1525);
FORCEPROP 1 LAST HDL_POWER GND
J 1
(650 1450);
DISPLAY 0.872340 (650 1450);
PAINT GREEN (650 1450);
DISPLAY INVISIBLE (650 1450);
FORCEPROP 1 LAST PATH I5
J 0
(700 1525);
DISPLAY 0.872340 (700 1525);
PAINT AQUA (700 1525);
DISPLAY INVISIBLE (700 1525);
FORCEADD Q_RES..1
(5175 4000);
FORCEPROP 1 LAST LOCATION PR280
J 0
(5125 4050);
DISPLAY 0.489362 (5125 4050);
PAINT SKYBLUE (5125 4050);
FORCEPROP 0 LAST $SEC 1
J 0
(5425 4125);
DISPLAY 0.680851 (5425 4125);
PAINT MONO (5425 4125);
DISPLAY INVISIBLE (5425 4125);
FORCEPROP 0 LAST CDS_SEC 1
J 0
(5425 4125);
DISPLAY 1.021277 (5425 4125);
DISPLAY INVISIBLE (5425 4125);
FORCEPROP 1 LASTPIN (5075 4000) $PN 1
J 0
(5087 4012);
DISPLAY 0.787234 (5087 4012);
PAINT MONO (5087 4012);
DISPLAY INVISIBLE (5087 4012);
FORCEPROP 1 LASTPIN (5275 4000) $PN 2
J 0
(5237 4012);
DISPLAY 0.787234 (5237 4012);
PAINT MONO (5237 4012);
DISPLAY INVISIBLE (5237 4012);
FORCEPROP 1 LAST TOLERANCE 5%
J 0
(4975 4050);
DISPLAY 0.489362 (4975 4050);
PAINT SKYBLUE (4975 4050);
FORCEPROP 1 LAST VALUE 0
J 2
(4950 4050);
DISPLAY 0.489362 (4950 4050);
PAINT SKYBLUE (4950 4050);
FORCEPROP 1 LAST WATTAGE 1/16W
J 2
(5400 4075);
DISPLAY 0.489362 (5400 4075);
PAINT SKYBLUE (5400 4075);
FORCEPROP 1 LAST MATERIAL CHIP
J 0
(5300 4025);
DISPLAY 0.489362 (5300 4025);
PAINT SKYBLUE (5300 4025);
FORCEPROP 1 LAST PACK_TYPE 0402LF
J 0
(5275 3950);
DISPLAY 0.489362 (5275 3950);
PAINT SKYBLUE (5275 3950);
FORCEPROP 2 LAST CDS_LIB pure_quanta
J 0
(5175 4000);
DISPLAY INVISIBLE (5175 4000);
FORCEPROP 1 LAST PATH I50
J 0
(5125 4150);
DISPLAY 0.978723 (5125 4150);
PAINT WHITE (5125 4150);
DISPLAY INVISIBLE (5125 4150);
FORCEPROP 1 LAST PART_NUMBER CS00002JB13
J 0
(4850 3950);
DISPLAY 0.489362 (4850 3950);
PAINT SKYBLUE (4850 3950);
DISPLAY INVISIBLE (4850 3950);
FORCEADD UNIVERSAL_GND..1
(5250 2825);
FORCEPROP 3 LASTPIN (5250 2875) SIG_NAME GND\g
J 0
(5260 2885);
DISPLAY 0.659574 (5260 2885);
PAINT MONO (5260 2885);
DISPLAY INVISIBLE (5260 2885);
FORCEPROP 2 LAST CDS_LIB pure_quanta_power
J 0
(5250 2825);
PAINT MONO (5250 2825);
DISPLAY INVISIBLE (5250 2825);
FORCEPROP 1 LAST HDL_POWER GND
J 1
(5275 2750);
DISPLAY 0.872340 (5275 2750);
PAINT GREEN (5275 2750);
DISPLAY INVISIBLE (5275 2750);
FORCEPROP 1 LAST PATH I51
J 0
(5325 2825);
DISPLAY 0.872340 (5325 2825);
PAINT AQUA (5325 2825);
DISPLAY INVISIBLE (5325 2825);
FORCEADD Q_CAP..1
(5250 3175);
FORCEPROP 1 LAST LOCATION PC449_2
J 0
(5325 3325);
DISPLAY 0.489362 (5325 3325);
PAINT SKYBLUE (5325 3325);
FORCEPROP 0 LAST $SEC 1
J 0
(5300 3325);
DISPLAY 0.680851 (5300 3325);
PAINT MONO (5300 3325);
DISPLAY INVISIBLE (5300 3325);
FORCEPROP 0 LAST CDS_SEC 1
J 0
(5300 3325);
DISPLAY 1.021277 (5300 3325);
DISPLAY INVISIBLE (5300 3325);
FORCEPROP 1 LASTPIN (5250 3275) $PN 1
J 0
(5260 3255);
DISPLAY 0.489362 (5260 3255);
PAINT MONO (5260 3255);
FORCEPROP 1 LASTPIN (5250 3075) $PN 2
J 0
(5260 3055);
DISPLAY 0.489362 (5260 3055);
PAINT MONO (5260 3055);
FORCEPROP 1 LAST PACK_TYPE C0805
J 0
(5325 3075);
DISPLAY 0.489362 (5325 3075);
PAINT SKYBLUE (5325 3075);
FORCEPROP 1 LAST VALUE 22UF
J 0
(5325 3275);
DISPLAY 0.489362 (5325 3275);
PAINT SKYBLUE (5325 3275);
FORCEPROP 1 LAST VOLTAGE 16V
J 0
(5325 3225);
DISPLAY 0.489362 (5325 3225);
PAINT SKYBLUE (5325 3225);
FORCEPROP 1 LAST TOLERANCE 20%
J 0
(5325 3175);
DISPLAY 0.489362 (5325 3175);
PAINT SKYBLUE (5325 3175);
FORCEPROP 1 LAST MATERIAL X6S
J 0
(5325 3125);
DISPLAY 0.489362 (5325 3125);
PAINT SKYBLUE (5325 3125);
FORCEPROP 2 LAST CDS_LIB pure_quanta
J 0
(5250 3175);
DISPLAY INVISIBLE (5250 3175);
FORCEPROP 1 LAST PATH I52
J 0
(5300 3325);
DISPLAY 0.978723 (5300 3325);
PAINT WHITE (5300 3325);
DISPLAY INVISIBLE (5300 3325);
FORCEPROP 1 LAST PART_NUMBER CH6223MEA01
J 0
(5325 3025);
DISPLAY 0.489362 (5325 3025);
PAINT SKYBLUE (5325 3025);
DISPLAY INVISIBLE (5325 3025);
FORCEADD VCC_CORE..1
(5250 3550);
FORCEPROP 3 LASTPIN (5250 3500) SIG_NAME SW_P12V_AUX_PVDDIO_P1_FLT\g
J 0
(5260 3510);
DISPLAY 0.659574 (5260 3510);
PAINT MONO (5260 3510);
DISPLAY INVISIBLE (5260 3510);
FORCEPROP 1 LAST HDL_POWER SW_P12V_AUX_PVDDIO_P1_FLT
J 1
(5250 3600);
DISPLAY 0.489362 (5250 3600);
PAINT GREEN (5250 3600);
FORCEPROP 2 LAST CDS_LIB pure_quanta_power
J 0
(5250 3550);
DISPLAY INVISIBLE (5250 3550);
FORCEPROP 1 LAST PATH I53
J 0
(5300 3575);
DISPLAY 0.872340 (5300 3575);
PAINT AQUA (5300 3575);
DISPLAY INVISIBLE (5300 3575);
FORCEADD OFFPAGE..3
(6900 2000);
FORCEPROP 2 LAST $XR0 222 
J 0
(7144 2000);
DISPLAY 0.638298 (7144 2000);
PAINT MONO (7144 2000);
FORCEPROP 2 LAST CDS_LIB standard
J 0
(6900 2000);
DISPLAY INVISIBLE (6900 2000);
FORCEPROP 1 LAST OFFPAGE TRUE
J 0
(7225 1875);
DISPLAY 0.872340 (7225 1875);
PAINT GREEN (7225 1875);
DISPLAY INVISIBLE (7225 1875);
FORCEPROP 1 LAST COMMENT_BODY TRUE
J 0
(6850 1900);
DISPLAY 0.872340 (6850 1900);
PAINT GREEN (6850 1900);
DISPLAY INVISIBLE (6850 1900);
FORCEPROP 2 LAST PATH I54
J 0
(7150 2050);
DISPLAY 0.680851 (7150 2050);
DISPLAY INVISIBLE (7150 2050);
FORCEADD Q_CAP..1
(7475 2050);
FORCEPROP 1 LAST LOCATION PC458_2
J 0
(7525 2175);
DISPLAY 0.489362 (7525 2175);
PAINT SKYBLUE (7525 2175);
FORCEPROP 0 LAST $SEC 1
J 0
(7525 2225);
DISPLAY 0.680851 (7525 2225);
PAINT MONO (7525 2225);
DISPLAY INVISIBLE (7525 2225);
FORCEPROP 0 LAST CDS_SEC 1
J 0
(7525 2225);
DISPLAY 1.021277 (7525 2225);
DISPLAY INVISIBLE (7525 2225);
FORCEPROP 1 LASTPIN (7475 2150) $PN 1
J 0
(7485 2130);
DISPLAY 0.489362 (7485 2130);
PAINT MONO (7485 2130);
FORCEPROP 1 LASTPIN (7475 1950) $PN 2
J 0
(7485 1930);
DISPLAY 0.489362 (7485 1930);
PAINT MONO (7485 1930);
FORCEPROP 1 LAST PACK_TYPE C0805
J 0
(7525 1925);
DISPLAY 0.489362 (7525 1925);
PAINT SKYBLUE (7525 1925);
FORCEPROP 1 LAST MATERIAL X6S
J 0
(7525 1975);
DISPLAY 0.489362 (7525 1975);
PAINT SKYBLUE (7525 1975);
FORCEPROP 1 LAST TOLERANCE 20%
J 0
(7525 2025);
DISPLAY 0.489362 (7525 2025);
PAINT SKYBLUE (7525 2025);
FORCEPROP 1 LAST VALUE 22UF
J 0
(7525 2125);
DISPLAY 0.489362 (7525 2125);
PAINT SKYBLUE (7525 2125);
FORCEPROP 1 LAST VOLTAGE 4V
J 0
(7525 2075);
DISPLAY 0.489362 (7525 2075);
PAINT SKYBLUE (7525 2075);
FORCEPROP 2 LAST CDS_LIB pure_quanta
J 0
(7475 2050);
DISPLAY INVISIBLE (7475 2050);
FORCEPROP 1 LAST PATH I55
J 0
(7525 2200);
DISPLAY 0.978723 (7525 2200);
PAINT WHITE (7525 2200);
DISPLAY INVISIBLE (7525 2200);
FORCEPROP 1 LAST PART_NUMBER CH622KMEA03
J 0
(7525 1875);
DISPLAY 0.489362 (7525 1875);
PAINT SKYBLUE (7525 1875);
DISPLAY INVISIBLE (7525 1875);
FORCEADD UNIVERSAL_GND..1
(7900 1700);
FORCEPROP 3 LASTPIN (7900 1750) SIG_NAME GND\g
J 0
(7910 1760);
DISPLAY 0.659574 (7910 1760);
PAINT MONO (7910 1760);
DISPLAY INVISIBLE (7910 1760);
FORCEPROP 2 LAST CDS_LIB pure_quanta_power
J 0
(7900 1700);
PAINT MONO (7900 1700);
DISPLAY INVISIBLE (7900 1700);
FORCEPROP 1 LAST HDL_POWER GND
J 1
(7925 1625);
DISPLAY 0.872340 (7925 1625);
PAINT GREEN (7925 1625);
DISPLAY INVISIBLE (7925 1625);
FORCEPROP 1 LAST PATH I56
J 0
(7975 1700);
DISPLAY 0.872340 (7975 1700);
PAINT AQUA (7975 1700);
DISPLAY INVISIBLE (7975 1700);
FORCEADD Q_CAP..1
(7900 2050);
FORCEPROP 1 LAST LOCATION PC460_2
J 0
(7950 2175);
DISPLAY 0.489362 (7950 2175);
PAINT SKYBLUE (7950 2175);
FORCEPROP 0 LAST $SEC 1
J 0
(7950 2225);
DISPLAY 0.680851 (7950 2225);
PAINT MONO (7950 2225);
DISPLAY INVISIBLE (7950 2225);
FORCEPROP 0 LAST CDS_SEC 1
J 0
(7950 2225);
DISPLAY 1.021277 (7950 2225);
DISPLAY INVISIBLE (7950 2225);
FORCEPROP 1 LASTPIN (7900 2150) $PN 1
J 0
(7910 2130);
DISPLAY 0.489362 (7910 2130);
PAINT MONO (7910 2130);
FORCEPROP 1 LASTPIN (7900 1950) $PN 2
J 0
(7910 1930);
DISPLAY 0.489362 (7910 1930);
PAINT MONO (7910 1930);
FORCEPROP 1 LAST PACK_TYPE C0805
J 0
(7950 1925);
DISPLAY 0.489362 (7950 1925);
PAINT SKYBLUE (7950 1925);
FORCEPROP 1 LAST MATERIAL X6S
J 0
(7950 1975);
DISPLAY 0.489362 (7950 1975);
PAINT SKYBLUE (7950 1975);
FORCEPROP 1 LAST TOLERANCE 20%
J 0
(7950 2025);
DISPLAY 0.489362 (7950 2025);
PAINT SKYBLUE (7950 2025);
FORCEPROP 1 LAST VALUE 22UF
J 0
(7950 2125);
DISPLAY 0.489362 (7950 2125);
PAINT SKYBLUE (7950 2125);
FORCEPROP 1 LAST VOLTAGE 4V
J 0
(7950 2075);
DISPLAY 0.489362 (7950 2075);
PAINT SKYBLUE (7950 2075);
FORCEPROP 2 LAST CDS_LIB pure_quanta
J 0
(7900 2050);
DISPLAY INVISIBLE (7900 2050);
FORCEPROP 1 LAST PATH I57
J 0
(7950 2200);
DISPLAY 0.978723 (7950 2200);
PAINT WHITE (7950 2200);
DISPLAY INVISIBLE (7950 2200);
FORCEPROP 1 LAST PART_NUMBER CH622KMEA03
J 0
(7950 1875);
DISPLAY 0.489362 (7950 1875);
PAINT SKYBLUE (7950 1875);
DISPLAY INVISIBLE (7950 1875);
FORCEADD Q_CAPP..1
(7000 3275);
FORCEPROP 1 LAST LOCATION PC450
J 0
(7050 3425);
DISPLAY 0.489362 (7050 3425);
PAINT SKYBLUE (7050 3425);
FORCEPROP 0 LAST $SEC 1
J 0
(7050 3450);
DISPLAY 0.680851 (7050 3450);
PAINT MONO (7050 3450);
DISPLAY INVISIBLE (7050 3450);
FORCEPROP 0 LAST CDS_SEC 1
J 0
(7050 3450);
DISPLAY 1.021277 (7050 3450);
DISPLAY INVISIBLE (7050 3450);
FORCEPROP 1 LASTPIN (7000 3375) $PN 1
J 0
(7010 3360);
DISPLAY 0.489362 (7010 3360);
PAINT MONO (7010 3360);
FORCEPROP 1 LASTPIN (7000 3175) $PN 2
J 0
(7010 3160);
DISPLAY 0.489362 (7010 3160);
PAINT MONO (7010 3160);
FORCEPROP 1 LAST PACK_TYPE SMLF
J 0
(7050 3175);
DISPLAY 0.489362 (7050 3175);
PAINT SKYBLUE (7050 3175);
FORCEPROP 1 LAST VOLTAGE 2.5V
J 0
(7050 3275);
DISPLAY 0.489362 (7050 3275);
PAINT SKYBLUE (7050 3275);
FORCEPROP 1 LAST VALUE 470UF
J 0
(7050 3375);
DISPLAY 0.489362 (7050 3375);
PAINT SKYBLUE (7050 3375);
FORCEPROP 1 LAST TOLERANCE 20%
J 0
(7050 3325);
DISPLAY 0.489362 (7050 3325);
PAINT SKYBLUE (7050 3325);
FORCEPROP 1 LAST MATERIAL SPCAP
J 0
(7050 3225);
DISPLAY 0.489362 (7050 3225);
PAINT SKYBLUE (7050 3225);
FORCEPROP 2 LAST CDS_LIB pure_quanta
J 0
(7000 3275);
DISPLAY INVISIBLE (7000 3275);
FORCEPROP 1 LAST PATH I58
J 0
(7050 3425);
DISPLAY 0.978723 (7050 3425);
DISPLAY INVISIBLE (7050 3425);
FORCEPROP 1 LAST PART_NUMBER CH747LM8825
J 0
(7050 3125);
DISPLAY 0.489362 (7050 3125);
PAINT SKYBLUE (7050 3125);
DISPLAY INVISIBLE (7050 3125);
FORCEADD Q_CAPP..1
(7400 3275);
FORCEPROP 1 LAST LOCATION PC452
J 0
(7450 3425);
DISPLAY 0.489362 (7450 3425);
PAINT SKYBLUE (7450 3425);
FORCEPROP 0 LAST $SEC 1
J 0
(7450 3475);
DISPLAY 0.680851 (7450 3475);
PAINT MONO (7450 3475);
DISPLAY INVISIBLE (7450 3475);
FORCEPROP 0 LAST CDS_SEC 1
J 0
(7450 3475);
DISPLAY 1.021277 (7450 3475);
DISPLAY INVISIBLE (7450 3475);
FORCEPROP 1 LASTPIN (7400 3375) $PN 1
J 0
(7410 3360);
DISPLAY 0.489362 (7410 3360);
PAINT MONO (7410 3360);
FORCEPROP 1 LASTPIN (7400 3175) $PN 2
J 0
(7410 3160);
DISPLAY 0.489362 (7410 3160);
PAINT MONO (7410 3160);
FORCEPROP 1 LAST VOLTAGE 2.5V
J 0
(7450 3275);
DISPLAY 0.489362 (7450 3275);
PAINT SKYBLUE (7450 3275);
FORCEPROP 1 LAST PACK_TYPE SMLF
J 0
(7450 3175);
DISPLAY 0.489362 (7450 3175);
PAINT SKYBLUE (7450 3175);
FORCEPROP 1 LAST VALUE 470UF
J 0
(7450 3375);
DISPLAY 0.489362 (7450 3375);
PAINT SKYBLUE (7450 3375);
FORCEPROP 1 LAST TOLERANCE 20%
J 0
(7450 3325);
DISPLAY 0.489362 (7450 3325);
PAINT SKYBLUE (7450 3325);
FORCEPROP 1 LAST MATERIAL SPCAP
J 0
(7450 3225);
DISPLAY 0.489362 (7450 3225);
PAINT SKYBLUE (7450 3225);
FORCEPROP 2 LAST CDS_LIB pure_quanta
J 0
(7400 3275);
DISPLAY INVISIBLE (7400 3275);
FORCEPROP 1 LAST PATH I59
J 0
(7450 3425);
DISPLAY 0.978723 (7450 3425);
DISPLAY INVISIBLE (7450 3425);
FORCEPROP 1 LAST PART_NUMBER CH747LM8825
J 0
(7450 3125);
DISPLAY 0.489362 (7450 3125);
PAINT SKYBLUE (7450 3125);
DISPLAY INVISIBLE (7450 3125);
FORCEADD Q_RES..2
R 2
(625 1750);
FORCEPROP 1 LAST LOCATION PR274
J 2
(580 1875);
DISPLAY 0.489362 (580 1875);
PAINT SKYBLUE (580 1875);
FORCEPROP 0 LAST $SEC 1
J 2
(575 1925);
DISPLAY 0.680851 (575 1925);
PAINT MONO (575 1925);
DISPLAY INVISIBLE (575 1925);
FORCEPROP 0 LAST CDS_SEC 1
J 2
(575 1925);
DISPLAY 1.021277 (575 1925);
DISPLAY INVISIBLE (575 1925);
FORCEPROP 1 LASTPIN (625 1850) $PN 1
J 2
(620 1812);
DISPLAY 0.489362 (620 1812);
PAINT MONO (620 1812);
FORCEPROP 1 LASTPIN (625 1650) $PN 2
J 2
(620 1660);
DISPLAY 0.489362 (620 1660);
PAINT MONO (620 1660);
FORCEPROP 1 LAST PACK_TYPE 0402LF
J 2
(575 1575);
DISPLAY 0.489362 (575 1575);
PAINT SKYBLUE (575 1575);
FORCEPROP 1 LAST VALUE 8.87K
J 2
(570 1825);
DISPLAY 0.489362 (570 1825);
PAINT SKYBLUE (570 1825);
FORCEPROP 1 LAST TOLERANCE 1%
J 2
(570 1775);
DISPLAY 0.489362 (570 1775);
PAINT SKYBLUE (570 1775);
FORCEPROP 1 LAST MATERIAL EMPTY
J 2
(575 1675);
DISPLAY 0.489362 (575 1675);
PAINT RED (575 1675);
FORCEPROP 1 LAST WATTAGE 1/16W
J 2
(575 1725);
DISPLAY 0.489362 (575 1725);
PAINT SKYBLUE (575 1725);
FORCEPROP 2 LAST CDS_LIB pure_quanta
J 2
(625 1750);
DISPLAY INVISIBLE (625 1750);
FORCEPROP 1 LAST PATH I6
J 2
(575 1925);
DISPLAY 0.978723 (575 1925);
PAINT WHITE (575 1925);
DISPLAY INVISIBLE (575 1925);
FORCEPROP 1 LAST PART_NUMBER CS28872FB01
J 2
(575 1625);
DISPLAY 0.489362 (575 1625);
PAINT SKYBLUE (575 1625);
DISPLAY INVISIBLE (575 1625);
FORCEADD VCC_CORE..1
(7900 2400);
FORCEPROP 3 LASTPIN (7900 2350) SIG_NAME PVDDIO_P1\g
J 0
(7910 2360);
DISPLAY 0.659574 (7910 2360);
PAINT MONO (7910 2360);
DISPLAY INVISIBLE (7910 2360);
FORCEPROP 1 LAST HDL_POWER PVDDIO_P1
J 1
(7900 2450);
DISPLAY 0.489362 (7900 2450);
PAINT GREEN (7900 2450);
FORCEPROP 2 LAST CDS_LIB pure_quanta_power
J 0
(7900 2400);
DISPLAY INVISIBLE (7900 2400);
FORCEPROP 1 LAST PATH I60
J 0
(7950 2425);
DISPLAY 0.872340 (7950 2425);
PAINT AQUA (7950 2425);
DISPLAY INVISIBLE (7950 2425);
FORCEADD UNIVERSAL_GND..1
(7800 2925);
FORCEPROP 3 LASTPIN (7800 2975) SIG_NAME GND\g
J 0
(7810 2985);
DISPLAY 0.659574 (7810 2985);
PAINT MONO (7810 2985);
DISPLAY INVISIBLE (7810 2985);
FORCEPROP 2 LAST CDS_LIB pure_quanta_power
J 0
(7800 2925);
PAINT MONO (7800 2925);
DISPLAY INVISIBLE (7800 2925);
FORCEPROP 1 LAST HDL_POWER GND
J 1
(7825 2850);
DISPLAY 0.872340 (7825 2850);
PAINT GREEN (7825 2850);
DISPLAY INVISIBLE (7825 2850);
FORCEPROP 1 LAST PATH I61
J 0
(7875 2925);
DISPLAY 0.872340 (7875 2925);
PAINT AQUA (7875 2925);
DISPLAY INVISIBLE (7875 2925);
FORCEADD Q_CAPP..1
(7800 3275);
FORCEPROP 1 LAST LOCATION PC455
J 0
(7875 3425);
DISPLAY 0.489362 (7875 3425);
PAINT SKYBLUE (7875 3425);
FORCEPROP 2 LAST $SEC 1
J 0
(7850 3475);
DISPLAY 0.680851 (7850 3475);
PAINT MONO (7850 3475);
DISPLAY INVISIBLE (7850 3475);
FORCEPROP 2 LAST CDS_SEC 1
J 0
(7850 3475);
DISPLAY 1.021277 (7850 3475);
DISPLAY INVISIBLE (7850 3475);
FORCEPROP 1 LASTPIN (7800 3375) $PN 1
J 0
(7810 3360);
DISPLAY 0.489362 (7810 3360);
PAINT MONO (7810 3360);
FORCEPROP 1 LASTPIN (7800 3175) $PN 2
J 0
(7810 3160);
DISPLAY 0.489362 (7810 3160);
PAINT MONO (7810 3160);
FORCEPROP 1 LAST PACK_TYPE SMLF
J 0
(7875 3175);
DISPLAY 0.489362 (7875 3175);
PAINT SKYBLUE (7875 3175);
FORCEPROP 1 LAST VOLTAGE 2.5V
J 0
(7875 3275);
DISPLAY 0.489362 (7875 3275);
PAINT SKYBLUE (7875 3275);
FORCEPROP 1 LAST VALUE 470UF
J 0
(7875 3375);
DISPLAY 0.489362 (7875 3375);
PAINT SKYBLUE (7875 3375);
FORCEPROP 1 LAST TOLERANCE 20%
J 0
(7875 3325);
DISPLAY 0.489362 (7875 3325);
PAINT SKYBLUE (7875 3325);
FORCEPROP 1 LAST MATERIAL EMPTY
J 0
(7875 3225);
DISPLAY 0.489362 (7875 3225);
PAINT RED (7875 3225);
FORCEPROP 2 LAST CDS_LIB pure_quanta
J 0
(7800 3275);
DISPLAY INVISIBLE (7800 3275);
FORCEPROP 1 LAST PATH I62
J 0
(7850 3425);
DISPLAY 0.978723 (7850 3425);
DISPLAY INVISIBLE (7850 3425);
FORCEPROP 1 LAST PART_NUMBER CH747LM8825
J 0
(7875 3125);
DISPLAY 0.489362 (7875 3125);
PAINT SKYBLUE (7875 3125);
DISPLAY INVISIBLE (7875 3125);
FORCEADD VCC_CORE..1
(7800 3600);
FORCEPROP 3 LASTPIN (7800 3550) SIG_NAME PVDDIO_P1\g
J 0
(7810 3560);
DISPLAY 0.659574 (7810 3560);
PAINT MONO (7810 3560);
DISPLAY INVISIBLE (7810 3560);
FORCEPROP 1 LAST HDL_POWER PVDDIO_P1
J 1
(7800 3650);
DISPLAY 0.489362 (7800 3650);
PAINT GREEN (7800 3650);
FORCEPROP 2 LAST CDS_LIB pure_quanta_power
J 0
(7800 3600);
DISPLAY INVISIBLE (7800 3600);
FORCEPROP 1 LAST PATH I63
J 0
(7850 3625);
DISPLAY 0.872340 (7850 3625);
PAINT AQUA (7850 3625);
DISPLAY INVISIBLE (7850 3625);
FORCEADD OFFPAGE..6
(4850 4750);
FORCEPROP 2 LAST $XR0 222 
J 0
(4570 4750);
DISPLAY 0.638298 (4570 4750);
PAINT MONO (4570 4750);
FORCEPROP 2 LAST CDS_LIB standard
J 0
(4850 4750);
DISPLAY INVISIBLE (4850 4750);
FORCEPROP 1 LAST OFFPAGE TRUE
J 0
(5175 4625);
DISPLAY 0.872340 (5175 4625);
PAINT GREEN (5175 4625);
DISPLAY INVISIBLE (5175 4625);
FORCEPROP 1 LAST COMMENT_BODY TRUE
J 0
(4950 4675);
DISPLAY 0.872340 (4950 4675);
PAINT GREEN (4950 4675);
DISPLAY INVISIBLE (4950 4675);
FORCEPROP 2 LAST PATH I64
J 0
(4550 4800);
DISPLAY 0.680851 (4550 4800);
DISPLAY INVISIBLE (4550 4800);
FORCEADD Q_CAP..1
(5000 5225);
FORCEPROP 1 LAST LOCATION PC447
J 0
(5050 5325);
DISPLAY 0.489362 (5050 5325);
PAINT SKYBLUE (5050 5325);
FORCEPROP 0 LAST $SEC 1
J 0
(5050 5375);
DISPLAY 0.680851 (5050 5375);
PAINT MONO (5050 5375);
DISPLAY INVISIBLE (5050 5375);
FORCEPROP 0 LAST CDS_SEC 1
J 2
(5050 5350);
DISPLAY 1.021277 (5050 5350);
DISPLAY INVISIBLE (5050 5350);
FORCEPROP 1 LASTPIN (5000 5325) $PN 1
J 0
(5010 5305);
DISPLAY 0.489362 (5010 5305);
PAINT MONO (5010 5305);
FORCEPROP 1 LASTPIN (5000 5125) $PN 2
J 0
(5010 5105);
DISPLAY 0.489362 (5010 5105);
PAINT MONO (5010 5105);
FORCEPROP 1 LAST PACK_TYPE 0402
J 0
(5050 5025);
DISPLAY 0.489362 (5050 5025);
PAINT SKYBLUE (5050 5025);
FORCEPROP 1 LAST VOLTAGE 16V
J 0
(5050 5225);
DISPLAY 0.489362 (5050 5225);
PAINT SKYBLUE (5050 5225);
FORCEPROP 1 LAST MATERIAL X7R
J 0
(5050 5125);
DISPLAY 0.489362 (5050 5125);
PAINT SKYBLUE (5050 5125);
FORCEPROP 1 LAST TOLERANCE 10%
J 0
(5050 5175);
DISPLAY 0.489362 (5050 5175);
PAINT SKYBLUE (5050 5175);
FORCEPROP 1 LAST VALUE 0.22UF
J 0
(5050 5275);
DISPLAY 0.489362 (5050 5275);
PAINT SKYBLUE (5050 5275);
FORCEPROP 2 LAST CDS_LIB pure_quanta
J 2
(5000 5225);
DISPLAY INVISIBLE (5000 5225);
FORCEPROP 1 LAST PATH I65
J 0
(5050 5375);
DISPLAY 0.978723 (5050 5375);
PAINT WHITE (5050 5375);
DISPLAY INVISIBLE (5050 5375);
FORCEPROP 1 LAST PART_NUMBER CH4223K1B00
J 0
(5050 5075);
DISPLAY 0.489362 (5050 5075);
PAINT SKYBLUE (5050 5075);
DISPLAY INVISIBLE (5050 5075);
FORCEADD Q_CAP..1
(4250 5900);
FORCEPROP 1 LAST LOCATION PC444_1
J 0
(4300 6050);
DISPLAY 0.489362 (4300 6050);
PAINT SKYBLUE (4300 6050);
FORCEPROP 0 LAST $SEC 1
J 0
(4300 6100);
DISPLAY 0.680851 (4300 6100);
PAINT MONO (4300 6100);
DISPLAY INVISIBLE (4300 6100);
FORCEPROP 0 LAST CDS_SEC 1
J 0
(4300 6100);
DISPLAY 1.021277 (4300 6100);
DISPLAY INVISIBLE (4300 6100);
FORCEPROP 1 LASTPIN (4250 6000) $PN 1
J 0
(4260 5980);
DISPLAY 0.489362 (4260 5980);
PAINT MONO (4260 5980);
FORCEPROP 1 LASTPIN (4250 5800) $PN 2
J 0
(4260 5780);
DISPLAY 0.489362 (4260 5780);
PAINT MONO (4260 5780);
FORCEPROP 1 LAST MATERIAL X6S
J 0
(4300 5850);
DISPLAY 0.489362 (4300 5850);
PAINT SKYBLUE (4300 5850);
FORCEPROP 1 LAST VOLTAGE 16V
J 0
(4300 5950);
DISPLAY 0.489362 (4300 5950);
PAINT SKYBLUE (4300 5950);
FORCEPROP 1 LAST VALUE 22UF
J 0
(4300 6000);
DISPLAY 0.489362 (4300 6000);
PAINT SKYBLUE (4300 6000);
FORCEPROP 1 LAST TOLERANCE 20%
J 0
(4300 5900);
DISPLAY 0.489362 (4300 5900);
PAINT SKYBLUE (4300 5900);
FORCEPROP 1 LAST PACK_TYPE C0805
J 0
(4300 5800);
DISPLAY 0.489362 (4300 5800);
PAINT SKYBLUE (4300 5800);
FORCEPROP 2 LAST CDS_LIB pure_quanta
J 0
(4250 5900);
DISPLAY INVISIBLE (4250 5900);
FORCEPROP 1 LAST PATH I66
J 0
(4300 6050);
DISPLAY 0.978723 (4300 6050);
PAINT WHITE (4300 6050);
DISPLAY INVISIBLE (4300 6050);
FORCEPROP 1 LAST PART_NUMBER CH6223MEA01
J 0
(4300 5750);
DISPLAY 0.382979 (4300 5750);
PAINT SKYBLUE (4300 5750);
DISPLAY INVISIBLE (4300 5750);
FORCEADD UNIVERSAL_GND..1
(4650 5525);
FORCEPROP 3 LASTPIN (4650 5575) SIG_NAME GND\g
J 0
(4660 5585);
DISPLAY 0.659574 (4660 5585);
PAINT MONO (4660 5585);
DISPLAY INVISIBLE (4660 5585);
FORCEPROP 2 LAST CDS_LIB pure_quanta_power
J 0
(4650 5525);
PAINT MONO (4650 5525);
DISPLAY INVISIBLE (4650 5525);
FORCEPROP 1 LAST HDL_POWER GND
J 1
(4675 5450);
DISPLAY 0.872340 (4675 5450);
PAINT GREEN (4675 5450);
DISPLAY INVISIBLE (4675 5450);
FORCEPROP 1 LAST PATH I67
J 0
(4725 5525);
DISPLAY 0.872340 (4725 5525);
PAINT AQUA (4725 5525);
DISPLAY INVISIBLE (4725 5525);
FORCEADD VCC_CORE..1
(4650 6250);
FORCEPROP 3 LASTPIN (4650 6200) SIG_NAME SW_P12V_AUX_PVDDIO_P1_FLT\g
J 0
(4660 6210);
DISPLAY 0.659574 (4660 6210);
PAINT MONO (4660 6210);
DISPLAY INVISIBLE (4660 6210);
FORCEPROP 1 LAST HDL_POWER SW_P12V_AUX_PVDDIO_P1_FLT
J 1
(4650 6300);
DISPLAY 0.489362 (4650 6300);
PAINT GREEN (4650 6300);
FORCEPROP 2 LAST CDS_LIB pure_quanta_power
J 0
(4650 6250);
DISPLAY INVISIBLE (4650 6250);
FORCEPROP 1 LAST PATH I68
J 0
(4700 6275);
DISPLAY 0.872340 (4700 6275);
PAINT AQUA (4700 6275);
DISPLAY INVISIBLE (4700 6275);
FORCEADD Q_CAP..1
(4775 5925);
FORCEPROP 1 LAST LOCATION PC448_1
J 0
(4825 6025);
DISPLAY 0.489362 (4825 6025);
PAINT SKYBLUE (4825 6025);
FORCEPROP 0 LAST $SEC 1
J 0
(4825 6075);
DISPLAY 0.680851 (4825 6075);
PAINT MONO (4825 6075);
DISPLAY INVISIBLE (4825 6075);
FORCEPROP 0 LAST CDS_SEC 1
J 0
(4825 6075);
DISPLAY 1.021277 (4825 6075);
DISPLAY INVISIBLE (4825 6075);
FORCEPROP 1 LASTPIN (4775 6025) $PN 1
J 0
(4785 6005);
DISPLAY 0.489362 (4785 6005);
PAINT MONO (4785 6005);
FORCEPROP 1 LASTPIN (4775 5825) $PN 2
J 0
(4785 5805);
DISPLAY 0.489362 (4785 5805);
PAINT MONO (4785 5805);
FORCEPROP 1 LAST PACK_TYPE C0805
J 0
(4825 5725);
DISPLAY 0.489362 (4825 5725);
PAINT SKYBLUE (4825 5725);
FORCEPROP 1 LAST VALUE 22UF
J 0
(4825 5975);
DISPLAY 0.489362 (4825 5975);
PAINT SKYBLUE (4825 5975);
FORCEPROP 1 LAST VOLTAGE 16V
J 0
(4825 5925);
DISPLAY 0.489362 (4825 5925);
PAINT SKYBLUE (4825 5925);
FORCEPROP 1 LAST TOLERANCE 20%
J 0
(4825 5875);
DISPLAY 0.489362 (4825 5875);
PAINT SKYBLUE (4825 5875);
FORCEPROP 1 LAST MATERIAL X6S
J 0
(4825 5825);
DISPLAY 0.489362 (4825 5825);
PAINT SKYBLUE (4825 5825);
FORCEPROP 2 LAST CDS_LIB pure_quanta
J 0
(4775 5925);
DISPLAY INVISIBLE (4775 5925);
FORCEPROP 1 LAST PATH I69
J 0
(4825 6075);
DISPLAY 0.978723 (4825 6075);
PAINT WHITE (4825 6075);
DISPLAY INVISIBLE (4825 6075);
FORCEPROP 1 LAST PART_NUMBER CH6223MEA01
J 0
(4825 5775);
DISPLAY 0.489362 (4825 5775);
PAINT SKYBLUE (4825 5775);
DISPLAY INVISIBLE (4825 5775);
FORCEADD OFFPAGE..1
(1100 1650);
FORCEPROP 2 LAST $XR0 217 
J 0
(818 1650);
DISPLAY 0.638298 (818 1650);
PAINT MONO (818 1650);
FORCEPROP 2 LAST CDS_LIB standard
J 0
(1100 1650);
DISPLAY INVISIBLE (1100 1650);
FORCEPROP 1 LAST OFFPAGE TRUE
J 0
(1425 1525);
DISPLAY 0.872340 (1425 1525);
PAINT GREEN (1425 1525);
DISPLAY INVISIBLE (1425 1525);
FORCEPROP 1 LAST COMMENT_BODY TRUE
J 0
(1225 1550);
DISPLAY 0.872340 (1225 1550);
PAINT GREEN (1225 1550);
DISPLAY INVISIBLE (1225 1550);
FORCEPROP 2 LAST PATH I7
J 0
(850 1700);
DISPLAY 0.680851 (850 1700);
DISPLAY INVISIBLE (850 1700);
FORCEADD Q_INDUCTOR4P_14..1
(5850 4875);
FORCEPROP 1 LAST LOCATION PL47
J 0
(5575 5050);
DISPLAY 0.489362 (5575 5050);
PAINT SKYBLUE (5575 5050);
FORCEPROP 0 LAST $SEC 1
J 0
(5900 5075);
DISPLAY 0.680851 (5900 5075);
PAINT MONO (5900 5075);
DISPLAY INVISIBLE (5900 5075);
FORCEPROP 0 LAST CDS_SEC 1
J 0
(5900 5075);
DISPLAY 1.021277 (5900 5075);
DISPLAY INVISIBLE (5900 5075);
FORCEPROP 0 LASTPIN (5450 5000) $PN 1
J 2
(5440 5010);
DISPLAY 0.489362 (5440 5010);
PAINT MONO (5440 5010);
FORCEPROP 0 LASTPIN (5450 4750) $PN 2
J 2
(5440 4760);
DISPLAY 0.489362 (5440 4760);
PAINT MONO (5440 4760);
FORCEPROP 0 LASTPIN (6250 4750) $PN 3
J 0
(6260 4760);
DISPLAY 0.489362 (6260 4760);
PAINT MONO (6260 4760);
FORCEPROP 0 LASTPIN (6250 5000) $PN 4
J 0
(6260 5010);
DISPLAY 0.489362 (6260 5010);
PAINT MONO (6260 5010);
FORCEPROP 2 LAST VALUE 150NH
J 0
(5750 5050);
DISPLAY 0.489362 (5750 5050);
PAINT SKYBLUE (5750 5050);
FORCEPROP 2 LAST PART_TYPE SMLF
J 0
(5775 4625);
DISPLAY 1.021277 (5775 4625);
FORCEPROP 1 LAST MATERIAL IND
J 0
(5650 5050);
DISPLAY 0.489362 (5650 5050);
PAINT SKYBLUE (5650 5050);
FORCEPROP 1 LAST NEEDS_NO_SIZE TRUE
J 0
(5850 4875);
DISPLAY 0.468085 (5850 4875);
PAINT GREEN (5850 4875);
DISPLAY INVISIBLE (5850 4875);
FORCEPROP 2 LAST CDS_LIB pure_quanta
J 0
(5850 4875);
DISPLAY INVISIBLE (5850 4875);
FORCEPROP 1 LAST PATH I71
J 0
(6050 5030);
DISPLAY 0.723404 (6050 5030);
PAINT GREEN (6050 5030);
DISPLAY INVISIBLE (6050 5030);
FORCEPROP 1 LAST PART_NUMBER CV+15^0TZ04
J 0
(5900 5050);
DISPLAY 0.489362 (5900 5050);
PAINT SKYBLUE (5900 5050);
DISPLAY INVISIBLE (5900 5050);
FORCEADD Q_INDUCTOR..1
(5450 6175);
FORCEPROP 1 LAST LOCATION PL49
J 0
(5300 6350);
DISPLAY 0.489362 (5300 6350);
PAINT SKYBLUE (5300 6350);
FORCEPROP 2 LAST $SEC 1
J 0
(5525 6275);
DISPLAY 0.680851 (5525 6275);
PAINT MONO (5525 6275);
DISPLAY INVISIBLE (5525 6275);
FORCEPROP 2 LAST CDS_SEC 1
J 0
(5525 6275);
DISPLAY 1.021277 (5525 6275);
DISPLAY INVISIBLE (5525 6275);
FORCEPROP 2 LASTPIN (5350 6150) $PN 1
J 2
(5340 6160);
DISPLAY 0.489362 (5340 6160);
FORCEPROP 2 LASTPIN (5550 6150) $PN 2
J 0
(5560 6160);
DISPLAY 0.489362 (5560 6160);
FORCEPROP 2 LAST PACK_TYPE SMLF
J 0
(5300 6400);
DISPLAY 0.489362 (5300 6400);
PAINT SKYBLUE (5300 6400);
FORCEPROP 2 LAST VALUE 50NH/86A
J 0
(5300 6450);
DISPLAY 0.489362 (5300 6450);
PAINT SKYBLUE (5300 6450);
FORCEPROP 1 LAST MATERIAL IND
J 0
(5300 6300);
DISPLAY 0.489362 (5300 6300);
PAINT SKYBLUE (5300 6300);
FORCEPROP 2 LAST CDS_LIB pure_quanta
J 0
(5450 6175);
PAINT MONO (5450 6175);
DISPLAY INVISIBLE (5450 6175);
FORCEPROP 1 LAST NEEDS_NO_SIZE TRUE
J 0
(5450 6175);
DISPLAY 0.468085 (5450 6175);
PAINT GREEN (5450 6175);
DISPLAY INVISIBLE (5450 6175);
FORCEPROP 1 LAST PATH I72
J 0
(5525 6230);
DISPLAY 0.723404 (5525 6230);
PAINT GREEN (5525 6230);
DISPLAY INVISIBLE (5525 6230);
FORCEPROP 1 LAST PART_NUMBER CVA50^0MZ09
J 0
(5300 6250);
DISPLAY 0.489362 (5300 6250);
PAINT SKYBLUE (5300 6250);
DISPLAY INVISIBLE (5300 6250);
FORCEADD UNIVERSAL_GND..1
(5850 5600);
FORCEPROP 3 LASTPIN (5850 5650) SIG_NAME GND\g
J 0
(5860 5660);
DISPLAY 0.659574 (5860 5660);
PAINT MONO (5860 5660);
DISPLAY INVISIBLE (5860 5660);
FORCEPROP 2 LAST CDS_LIB pure_quanta_power
J 0
(5850 5600);
DISPLAY INVISIBLE (5850 5600);
FORCEPROP 1 LAST HDL_POWER GND
J 1
(5875 5525);
DISPLAY 0.872340 (5875 5525);
PAINT GREEN (5875 5525);
DISPLAY INVISIBLE (5875 5525);
FORCEPROP 1 LAST PATH I73
J 0
(5925 5600);
DISPLAY 0.872340 (5925 5600);
PAINT AQUA (5925 5600);
DISPLAY INVISIBLE (5925 5600);
FORCEADD Q_CAP..1
(5850 5950);
FORCEPROP 1 LAST LOCATION PC438
J 0
(5900 6100);
DISPLAY 0.489362 (5900 6100);
PAINT SKYBLUE (5900 6100);
FORCEPROP 0 LAST $SEC 1
J 0
(5900 6125);
DISPLAY 0.680851 (5900 6125);
PAINT MONO (5900 6125);
DISPLAY INVISIBLE (5900 6125);
FORCEPROP 0 LAST CDS_SEC 1
J 0
(5900 6125);
DISPLAY 0.680851 (5900 6125);
DISPLAY INVISIBLE (5900 6125);
FORCEPROP 1 LASTPIN (5850 6050) $PN 1
J 0
(5860 6030);
DISPLAY 0.787234 (5860 6030);
PAINT MONO (5860 6030);
FORCEPROP 1 LASTPIN (5850 5850) $PN 2
J 0
(5860 5830);
DISPLAY 0.787234 (5860 5830);
PAINT MONO (5860 5830);
FORCEPROP 1 LAST PACK_TYPE 0402
J 0
(5900 5800);
DISPLAY 0.489362 (5900 5800);
PAINT SKYBLUE (5900 5800);
FORCEPROP 1 LAST MATERIAL X7R
J 0
(5900 5900);
DISPLAY 0.489362 (5900 5900);
PAINT SKYBLUE (5900 5900);
FORCEPROP 1 LAST VOLTAGE 25V
J 0
(5900 6000);
DISPLAY 0.489362 (5900 6000);
PAINT SKYBLUE (5900 6000);
FORCEPROP 1 LAST VALUE 0.1UF
J 0
(5900 6050);
DISPLAY 0.489362 (5900 6050);
PAINT SKYBLUE (5900 6050);
FORCEPROP 1 LAST TOLERANCE 10%
J 0
(5900 5950);
DISPLAY 0.489362 (5900 5950);
PAINT SKYBLUE (5900 5950);
FORCEPROP 2 LAST CDS_LIB pure_quanta
J 0
(5850 5950);
DISPLAY INVISIBLE (5850 5950);
FORCEPROP 1 LAST PATH I74
J 0
(5900 6100);
DISPLAY 0.978723 (5900 6100);
PAINT WHITE (5900 6100);
DISPLAY INVISIBLE (5900 6100);
FORCEPROP 1 LAST PART_NUMBER CH4104K1B00
J 0
(5900 5850);
DISPLAY 0.489362 (5900 5850);
PAINT SKYBLUE (5900 5850);
DISPLAY INVISIBLE (5900 5850);
FORCEADD VCC_CORE..1
(5850 6275);
FORCEPROP 3 LASTPIN (5850 6225) SIG_NAME P12V_AUX\g
J 0
(5860 6235);
DISPLAY 0.659574 (5860 6235);
PAINT MONO (5860 6235);
DISPLAY INVISIBLE (5860 6235);
FORCEPROP 1 LAST HDL_POWER P12V_AUX
J 1
(5850 6325);
DISPLAY 0.489362 (5850 6325);
PAINT GREEN (5850 6325);
FORCEPROP 2 LAST CDS_LIB pure_quanta_power
J 0
(5850 6275);
DISPLAY INVISIBLE (5850 6275);
FORCEPROP 1 LAST PATH I75
J 0
(5900 6300);
DISPLAY 0.872340 (5900 6300);
PAINT AQUA (5900 6300);
DISPLAY INVISIBLE (5900 6300);
FORCEADD UNIVERSAL_GND..1
(6775 4625);
FORCEPROP 3 LASTPIN (6775 4675) SIG_NAME GND\g
J 0
(6785 4685);
DISPLAY 0.659574 (6785 4685);
PAINT MONO (6785 4685);
DISPLAY INVISIBLE (6785 4685);
FORCEPROP 2 LAST CDS_LIB pure_quanta_power
J 0
(6775 4625);
DISPLAY INVISIBLE (6775 4625);
FORCEPROP 1 LAST HDL_POWER GND
J 1
(6800 4550);
DISPLAY 0.872340 (6800 4550);
PAINT GREEN (6800 4550);
DISPLAY INVISIBLE (6800 4550);
FORCEPROP 1 LAST PATH I76
J 0
(6850 4625);
DISPLAY 0.872340 (6850 4625);
PAINT AQUA (6850 4625);
DISPLAY INVISIBLE (6850 4625);
FORCEADD Q_CAP..1
(7175 4800);
FORCEPROP 1 LAST LOCATION PC451
J 0
(7225 4925);
DISPLAY 0.489362 (7225 4925);
PAINT SKYBLUE (7225 4925);
FORCEPROP 0 LAST $SEC 1
J 0
(7225 4975);
DISPLAY 0.680851 (7225 4975);
PAINT MONO (7225 4975);
DISPLAY INVISIBLE (7225 4975);
FORCEPROP 0 LAST CDS_SEC 1
J 0
(7225 4975);
DISPLAY 1.021277 (7225 4975);
DISPLAY INVISIBLE (7225 4975);
FORCEPROP 1 LASTPIN (7175 4900) $PN 1
J 0
(7185 4880);
DISPLAY 0.489362 (7185 4880);
PAINT MONO (7185 4880);
FORCEPROP 1 LASTPIN (7175 4700) $PN 2
J 0
(7185 4680);
DISPLAY 0.489362 (7185 4680);
PAINT MONO (7185 4680);
FORCEPROP 1 LAST PACK_TYPE C0402
J 0
(7225 4675);
DISPLAY 0.489362 (7225 4675);
PAINT SKYBLUE (7225 4675);
FORCEPROP 1 LAST VOLTAGE 50V
J 0
(7225 4825);
DISPLAY 0.489362 (7225 4825);
PAINT SKYBLUE (7225 4825);
FORCEPROP 1 LAST VALUE 100NF
J 0
(7225 4875);
DISPLAY 0.489362 (7225 4875);
PAINT SKYBLUE (7225 4875);
FORCEPROP 1 LAST TOLERANCE 10%
J 0
(7225 4775);
DISPLAY 0.489362 (7225 4775);
PAINT SKYBLUE (7225 4775);
FORCEPROP 1 LAST MATERIAL X7R
J 0
(7225 4725);
DISPLAY 0.489362 (7225 4725);
PAINT SKYBLUE (7225 4725);
FORCEPROP 2 LAST CDS_LIB pure_quanta
J 0
(7175 4800);
DISPLAY INVISIBLE (7175 4800);
FORCEPROP 1 LAST PATH I77
J 0
(7225 4950);
DISPLAY 0.978723 (7225 4950);
PAINT WHITE (7225 4950);
DISPLAY INVISIBLE (7225 4950);
FORCEPROP 1 LAST PART_NUMBER CH4106K1B01
J 0
(7225 4625);
DISPLAY 0.489362 (7225 4625);
PAINT SKYBLUE (7225 4625);
DISPLAY INVISIBLE (7225 4625);
FORCEADD Q_CAP..1
(7500 4800);
FORCEPROP 1 LAST LOCATION PC456_1
J 0
(7550 4925);
DISPLAY 0.489362 (7550 4925);
PAINT SKYBLUE (7550 4925);
FORCEPROP 0 LAST $SEC 1
J 0
(7550 4975);
DISPLAY 0.680851 (7550 4975);
PAINT MONO (7550 4975);
DISPLAY INVISIBLE (7550 4975);
FORCEPROP 0 LAST CDS_SEC 1
J 0
(7550 4975);
DISPLAY 1.021277 (7550 4975);
DISPLAY INVISIBLE (7550 4975);
FORCEPROP 1 LASTPIN (7500 4900) $PN 1
J 0
(7510 4880);
DISPLAY 0.489362 (7510 4880);
PAINT MONO (7510 4880);
FORCEPROP 1 LASTPIN (7500 4700) $PN 2
J 0
(7510 4680);
DISPLAY 0.489362 (7510 4680);
PAINT MONO (7510 4680);
FORCEPROP 1 LAST PACK_TYPE C0805
J 0
(7550 4675);
DISPLAY 0.489362 (7550 4675);
PAINT SKYBLUE (7550 4675);
FORCEPROP 1 LAST VOLTAGE 4V
J 0
(7550 4825);
DISPLAY 0.489362 (7550 4825);
PAINT SKYBLUE (7550 4825);
FORCEPROP 1 LAST VALUE 22UF
J 0
(7550 4875);
DISPLAY 0.489362 (7550 4875);
PAINT SKYBLUE (7550 4875);
FORCEPROP 1 LAST TOLERANCE 20%
J 0
(7550 4775);
DISPLAY 0.489362 (7550 4775);
PAINT SKYBLUE (7550 4775);
FORCEPROP 1 LAST MATERIAL X6S
J 0
(7550 4725);
DISPLAY 0.489362 (7550 4725);
PAINT SKYBLUE (7550 4725);
FORCEPROP 2 LAST CDS_LIB pure_quanta
J 0
(7500 4800);
DISPLAY INVISIBLE (7500 4800);
FORCEPROP 1 LAST PATH I78
J 0
(7550 4950);
DISPLAY 0.978723 (7550 4950);
PAINT WHITE (7550 4950);
DISPLAY INVISIBLE (7550 4950);
FORCEPROP 1 LAST PART_NUMBER CH622KMEA03
J 0
(7550 4625);
DISPLAY 0.489362 (7550 4625);
PAINT SKYBLUE (7550 4625);
DISPLAY INVISIBLE (7550 4625);
FORCEADD Q_CAP..1
(7950 4800);
FORCEPROP 1 LAST LOCATION PC459_1
J 0
(8000 4925);
DISPLAY 0.489362 (8000 4925);
PAINT SKYBLUE (8000 4925);
FORCEPROP 0 LAST $SEC 1
J 0
(8000 4975);
DISPLAY 0.680851 (8000 4975);
PAINT MONO (8000 4975);
DISPLAY INVISIBLE (8000 4975);
FORCEPROP 0 LAST CDS_SEC 1
J 0
(8000 4975);
DISPLAY 1.021277 (8000 4975);
DISPLAY INVISIBLE (8000 4975);
FORCEPROP 1 LASTPIN (7950 4900) $PN 1
J 0
(7960 4880);
DISPLAY 0.489362 (7960 4880);
PAINT MONO (7960 4880);
FORCEPROP 1 LASTPIN (7950 4700) $PN 2
J 0
(7960 4680);
DISPLAY 0.489362 (7960 4680);
PAINT MONO (7960 4680);
FORCEPROP 1 LAST PACK_TYPE C0805
J 0
(8000 4675);
DISPLAY 0.489362 (8000 4675);
PAINT SKYBLUE (8000 4675);
FORCEPROP 1 LAST MATERIAL X6S
J 0
(8000 4725);
DISPLAY 0.489362 (8000 4725);
PAINT SKYBLUE (8000 4725);
FORCEPROP 1 LAST TOLERANCE 20%
J 0
(8000 4775);
DISPLAY 0.489362 (8000 4775);
PAINT SKYBLUE (8000 4775);
FORCEPROP 1 LAST VALUE 22UF
J 0
(8000 4875);
DISPLAY 0.489362 (8000 4875);
PAINT SKYBLUE (8000 4875);
FORCEPROP 1 LAST VOLTAGE 4V
J 0
(8000 4825);
DISPLAY 0.489362 (8000 4825);
PAINT SKYBLUE (8000 4825);
FORCEPROP 2 LAST CDS_LIB pure_quanta
J 0
(7950 4800);
DISPLAY INVISIBLE (7950 4800);
FORCEPROP 1 LAST PATH I79
J 0
(8000 4950);
DISPLAY 0.978723 (8000 4950);
PAINT WHITE (8000 4950);
DISPLAY INVISIBLE (8000 4950);
FORCEPROP 1 LAST PART_NUMBER CH622KMEA03
J 0
(8000 4625);
DISPLAY 0.489362 (8000 4625);
PAINT SKYBLUE (8000 4625);
DISPLAY INVISIBLE (8000 4625);
FORCEADD OFFPAGE..5
(1100 1750);
FORCEPROP 2 LAST $XR2 217 
J 0
(845 1786);
DISPLAY 0.638298 (845 1786);
PAINT MONO (845 1786);
FORCEPROP 2 LAST $XR1 223 
J 0
(845 1714);
DISPLAY 0.638298 (845 1714);
PAINT MONO (845 1714);
FORCEPROP 2 LAST $XR0 222 
J 0
(845 1750);
DISPLAY 0.638298 (845 1750);
PAINT MONO (845 1750);
FORCEPROP 2 LAST CDS_LIB standard
J 0
(1100 1750);
DISPLAY INVISIBLE (1100 1750);
FORCEPROP 1 LAST OFFPAGE TRUE
J 0
(1425 1625);
DISPLAY 0.872340 (1425 1625);
PAINT GREEN (1425 1625);
DISPLAY INVISIBLE (1425 1625);
FORCEPROP 1 LAST COMMENT_BODY TRUE
J 0
(1200 1675);
DISPLAY 0.872340 (1200 1675);
PAINT GREEN (1200 1675);
DISPLAY INVISIBLE (1200 1675);
FORCEPROP 2 LAST PATH I8
J 0
(850 1825);
DISPLAY 0.680851 (850 1825);
DISPLAY INVISIBLE (850 1825);
FORCEADD UNIVERSAL_GND..1
(8250 4450);
FORCEPROP 3 LASTPIN (8250 4500) SIG_NAME GND\g
J 0
(8260 4510);
DISPLAY 0.659574 (8260 4510);
PAINT MONO (8260 4510);
DISPLAY INVISIBLE (8260 4510);
FORCEPROP 2 LAST CDS_LIB pure_quanta_power
J 0
(8250 4450);
PAINT MONO (8250 4450);
DISPLAY INVISIBLE (8250 4450);
FORCEPROP 1 LAST HDL_POWER GND
J 1
(8275 4375);
DISPLAY 0.872340 (8275 4375);
PAINT GREEN (8275 4375);
DISPLAY INVISIBLE (8275 4375);
FORCEPROP 1 LAST PATH I80
J 0
(8325 4450);
DISPLAY 0.872340 (8325 4450);
PAINT AQUA (8325 4450);
DISPLAY INVISIBLE (8325 4450);
FORCEADD Q_RES..2
(8250 4800);
FORCEPROP 1 LAST LOCATION PR378
J 0
(8295 4925);
DISPLAY 0.489362 (8295 4925);
PAINT SKYBLUE (8295 4925);
FORCEPROP 0 LAST $SEC 1
J 0
(8300 4950);
DISPLAY 0.680851 (8300 4950);
PAINT MONO (8300 4950);
DISPLAY INVISIBLE (8300 4950);
FORCEPROP 0 LAST CDS_SEC 1
J 0
(8300 4950);
DISPLAY 1.021277 (8300 4950);
DISPLAY INVISIBLE (8300 4950);
FORCEPROP 1 LASTPIN (8250 4900) $PN 1
J 0
(8255 4862);
DISPLAY 0.787234 (8255 4862);
PAINT MONO (8255 4862);
DISPLAY INVISIBLE (8255 4862);
FORCEPROP 1 LASTPIN (8250 4700) $PN 2
J 0
(8255 4710);
DISPLAY 0.787234 (8255 4710);
PAINT MONO (8255 4710);
DISPLAY INVISIBLE (8255 4710);
FORCEPROP 1 LAST WATTAGE 1/16W
J 0
(8290 4775);
DISPLAY 0.489362 (8290 4775);
PAINT SKYBLUE (8290 4775);
FORCEPROP 1 LAST MATERIAL CHIP
J 0
(8290 4725);
DISPLAY 0.489362 (8290 4725);
PAINT SKYBLUE (8290 4725);
FORCEPROP 1 LAST TOLERANCE 1%
J 0
(8295 4825);
DISPLAY 0.489362 (8295 4825);
PAINT SKYBLUE (8295 4825);
FORCEPROP 1 LAST VALUE 1K
J 0
(8295 4875);
DISPLAY 0.489362 (8295 4875);
PAINT SKYBLUE (8295 4875);
FORCEPROP 1 LAST PACK_TYPE 0402LF
J 0
(8290 4625);
DISPLAY 0.489362 (8290 4625);
PAINT SKYBLUE (8290 4625);
FORCEPROP 2 LAST CDS_LIB pure_quanta
J 0
(8250 4800);
DISPLAY INVISIBLE (8250 4800);
FORCEPROP 1 LAST PATH I81
J 0
(8300 4975);
DISPLAY 0.978723 (8300 4975);
PAINT WHITE (8300 4975);
DISPLAY INVISIBLE (8300 4975);
FORCEPROP 1 LAST PART_NUMBER CS21002FB06
J 0
(8290 4675);
DISPLAY 0.489362 (8290 4675);
PAINT SKYBLUE (8290 4675);
DISPLAY INVISIBLE (8290 4675);
FORCEADD VCC_CORE..1
(8250 5100);
FORCEPROP 3 LASTPIN (8250 5050) SIG_NAME PVDDIO_P1\g
J 0
(8260 5060);
DISPLAY 0.659574 (8260 5060);
PAINT MONO (8260 5060);
DISPLAY INVISIBLE (8260 5060);
FORCEPROP 1 LAST HDL_POWER PVDDIO_P1
J 1
(8250 5150);
DISPLAY 0.489362 (8250 5150);
PAINT GREEN (8250 5150);
FORCEPROP 2 LAST CDS_LIB pure_quanta_power
J 0
(8250 5100);
DISPLAY INVISIBLE (8250 5100);
FORCEPROP 1 LAST PATH I82
J 0
(8300 5125);
DISPLAY 0.872340 (8300 5125);
PAINT AQUA (8300 5125);
DISPLAY INVISIBLE (8300 5125);
FORCEADD Q_INDUCTOR4P_14..1
(6025 2125);
FORCEPROP 1 LAST LOCATION PL48
J 0
(5700 2300);
DISPLAY 0.489362 (5700 2300);
PAINT SKYBLUE (5700 2300);
FORCEPROP 0 LAST $SEC 1
J 0
(6075 2325);
DISPLAY 0.680851 (6075 2325);
PAINT MONO (6075 2325);
DISPLAY INVISIBLE (6075 2325);
FORCEPROP 0 LAST CDS_SEC 1
J 0
(6075 2325);
DISPLAY 1.021277 (6075 2325);
DISPLAY INVISIBLE (6075 2325);
FORCEPROP 0 LASTPIN (5625 2250) $PN 1
J 2
(5615 2260);
DISPLAY 0.489362 (5615 2260);
PAINT MONO (5615 2260);
FORCEPROP 0 LASTPIN (5625 2000) $PN 2
J 2
(5615 2010);
DISPLAY 0.489362 (5615 2010);
PAINT MONO (5615 2010);
FORCEPROP 0 LASTPIN (6425 2000) $PN 3
J 0
(6435 2010);
DISPLAY 0.489362 (6435 2010);
PAINT MONO (6435 2010);
FORCEPROP 0 LASTPIN (6425 2250) $PN 4
J 0
(6435 2260);
DISPLAY 0.489362 (6435 2260);
PAINT MONO (6435 2260);
FORCEPROP 2 LAST VALUE 150NH
J 0
(5925 2300);
DISPLAY 0.489362 (5925 2300);
PAINT SKYBLUE (5925 2300);
FORCEPROP 1 LAST MATERIAL IND
J 0
(5825 2300);
DISPLAY 0.489362 (5825 2300);
PAINT SKYBLUE (5825 2300);
FORCEPROP 2 LAST PART_TYPE SMLF
J 0
(5950 1875);
DISPLAY 1.021277 (5950 1875);
FORCEPROP 1 LAST NEEDS_NO_SIZE TRUE
J 0
(6025 2125);
DISPLAY 0.468085 (6025 2125);
PAINT GREEN (6025 2125);
DISPLAY INVISIBLE (6025 2125);
FORCEPROP 2 LAST CDS_LIB pure_quanta
J 0
(6025 2125);
DISPLAY INVISIBLE (6025 2125);
FORCEPROP 1 LAST PATH I83
J 0
(6225 2280);
DISPLAY 0.723404 (6225 2280);
PAINT GREEN (6225 2280);
DISPLAY INVISIBLE (6225 2280);
FORCEPROP 1 LAST PART_NUMBER CV+15^0TZ04
J 0
(6075 2300);
DISPLAY 0.489362 (6075 2300);
PAINT SKYBLUE (6075 2300);
DISPLAY INVISIBLE (6075 2300);
FORCEADD ISL99390FRZTR5935..1
(2650 2250);
FORCEPROP 1 LAST LOCATION PU40
J 0
(2350 3125);
DISPLAY 0.489362 (2350 3125);
PAINT SKYBLUE (2350 3125);
FORCEPROP 2 LAST $SEC 1
J 0
(2350 3175);
DISPLAY 0.680851 (2350 3175);
PAINT MONO (2350 3175);
DISPLAY INVISIBLE (2350 3175);
FORCEPROP 2 LAST CDS_SEC 1
J 0
(2400 3250);
DISPLAY 1.021277 (2400 3250);
DISPLAY INVISIBLE (2400 3250);
FORCEPROP 2 LASTPIN (3050 1800) $PN 2
J 0
(3060 1810);
DISPLAY 0.489362 (3060 1810);
PAINT MONO (3060 1810);
FORCEPROP 2 LASTPIN (3050 2600) $PN 33
J 0
(3060 2610);
DISPLAY 0.489362 (3060 2610);
PAINT MONO (3060 2610);
FORCEPROP 2 LASTPIN (2200 2000) $PN 31
J 2
(2190 2010);
DISPLAY 0.489362 (2190 2010);
PAINT MONO (2190 2010);
FORCEPROP 2 LASTPIN (2200 2400) $PN 35
J 2
(2190 2410);
DISPLAY 0.489362 (2190 2410);
PAINT MONO (2190 2410);
FORCEPROP 2 LASTPIN (3050 1950) $PN 6
J 0
(3060 1960);
DISPLAY 0.489362 (3060 1960);
PAINT MONO (3060 1960);
FORCEPROP 2 LASTPIN (3050 1900) $PN 41
J 0
(3060 1910);
DISPLAY 0.489362 (3060 1910);
PAINT MONO (3060 1910);
FORCEPROP 2 LASTPIN (2200 2250) $PN 38
J 2
(2190 2260);
DISPLAY 0.489362 (2190 2260);
PAINT MONO (2190 2260);
FORCEPROP 2 LASTPIN (2200 1950) $PN 37
J 2
(2190 1960);
DISPLAY 0.489362 (2190 1960);
PAINT MONO (2190 1960);
FORCEPROP 2 LASTPIN (3050 1750) $PN 5
J 0
(3060 1760);
DISPLAY 0.489362 (3060 1760);
PAINT MONO (3060 1760);
FORCEPROP 2 LASTPIN (3050 1700) $PN 7_9-20_24
J 0
(3060 1710);
DISPLAY 0.489362 (3060 1710);
PAINT MONO (3060 1710);
FORCEPROP 2 LASTPIN (3050 1650) $PN 40
J 0
(3060 1660);
DISPLAY 0.489362 (3060 1660);
PAINT MONO (3060 1660);
FORCEPROP 2 LASTPIN (3050 2350) $PN 32
J 0
(3060 2360);
DISPLAY 0.489362 (3060 2360);
PAINT MONO (3060 2360);
FORCEPROP 2 LASTPIN (2200 2900) $PN 4
J 2
(2190 2910);
DISPLAY 0.489362 (2190 2910);
PAINT MONO (2190 2910);
FORCEPROP 2 LASTPIN (2200 1650) $PN 34
J 2
(2190 1660);
DISPLAY 0.489362 (2190 1660);
PAINT MONO (2190 1660);
FORCEPROP 2 LASTPIN (2200 2150) $PN 39
J 2
(2190 2160);
DISPLAY 0.489362 (2190 2160);
PAINT MONO (2190 2160);
FORCEPROP 2 LASTPIN (3050 2250) $PN 10_19
J 0
(3060 2260);
DISPLAY 0.489362 (3060 2260);
PAINT MONO (3060 2260);
FORCEPROP 2 LASTPIN (2200 1750) $PN 36
J 2
(2190 1760);
DISPLAY 0.489362 (2190 1760);
PAINT MONO (2190 1760);
FORCEPROP 2 LASTPIN (2200 2600) $PN 3
J 2
(2190 2610);
DISPLAY 0.489362 (2190 2610);
PAINT MONO (2190 2610);
FORCEPROP 2 LASTPIN (3050 2900) $PN 25_29
J 0
(3060 2910);
DISPLAY 0.489362 (3060 2910);
PAINT MONO (3060 2910);
FORCEPROP 2 LASTPIN (3050 2850) $PN 30
J 0
(3060 2860);
DISPLAY 0.489362 (3060 2860);
PAINT MONO (3060 2860);
FORCEPROP 2 LASTPIN (3050 2000) $PN 1
J 0
(3060 2010);
DISPLAY 0.489362 (3060 2010);
PAINT MONO (3060 2010);
FORCEPROP 2 LAST VALUE ISL99390FRZ-TR5935
J 0
(2350 3200);
DISPLAY 0.489362 (2350 3200);
PAINT SKYBLUE (2350 3200);
FORCEPROP 1 LAST MATERIAL IC
J 0
(2350 2975);
DISPLAY 0.489362 (2350 2975);
PAINT SKYBLUE (2350 2975);
FORCEPROP 2 LAST PART_TYPE SMLF
J 0
(2350 3250);
DISPLAY 0.638298 (2350 3250);
FORCEPROP 1 LAST NEEDS_NO_SIZE TRUE
J 0
(2650 2250);
DISPLAY 0.723404 (2650 2250);
PAINT GREEN (2650 2250);
DISPLAY INVISIBLE (2650 2250);
FORCEPROP 1 LAST CDS_LMAN_SYM_OUTLINE -300,700,250,-650
J 0
(2650 2250);
DISPLAY 0.468085 (2650 2250);
PAINT GREEN (2650 2250);
DISPLAY INVISIBLE (2650 2250);
FORCEPROP 2 LAST CDS_LIB pure_quanta
J 0
(2650 2250);
DISPLAY INVISIBLE (2650 2250);
FORCEPROP 1 LAST PATH I84
J 0
(2650 2250);
DISPLAY 0.723404 (2650 2250);
PAINT GREEN (2650 2250);
DISPLAY INVISIBLE (2650 2250);
FORCEPROP 1 LAST PART_NUMBER AL099390004
J 0
(2350 3050);
DISPLAY 0.489362 (2350 3050);
PAINT SKYBLUE (2350 3050);
DISPLAY INVISIBLE (2350 3050);
FORCEADD Q_CAPP..1
(5075 5925);
FORCEPROP 1 LAST LOCATION PC454
J 0
(5125 6025);
DISPLAY 0.510638 (5125 6025);
FORCEPROP 0 LAST $SEC 1
J 0
(5125 6050);
DISPLAY 0.680851 (5125 6050);
PAINT MONO (5125 6050);
DISPLAY INVISIBLE (5125 6050);
FORCEPROP 0 LAST CDS_SEC 1
J 0
(5125 6050);
DISPLAY 0.680851 (5125 6050);
DISPLAY INVISIBLE (5125 6050);
FORCEPROP 1 LASTPIN (5075 6025) $PN 1
J 0
(5085 6010);
DISPLAY 0.787234 (5085 6010);
PAINT MONO (5085 6010);
FORCEPROP 1 LASTPIN (5075 5825) $PN 2
J 0
(5085 5810);
DISPLAY 0.787234 (5085 5810);
PAINT MONO (5085 5810);
FORCEPROP 1 LAST MATERIAL OSCON
J 0
(5125 5825);
DISPLAY 0.510638 (5125 5825);
FORCEPROP 1 LAST PACK_TYPE SMLF
J 0
(5125 5775);
DISPLAY 0.510638 (5125 5775);
FORCEPROP 1 LAST VOLTAGE 16V
J 0
(5125 5875);
DISPLAY 0.510638 (5125 5875);
FORCEPROP 1 LAST VALUE 270UF
J 0
(5125 5975);
DISPLAY 0.510638 (5125 5975);
FORCEPROP 1 LAST TOLERANCE 20%
J 0
(5125 5925);
DISPLAY 0.510638 (5125 5925);
FORCEPROP 2 LAST CDS_LIB pure_quanta
J 0
(5075 5925);
DISPLAY INVISIBLE (5075 5925);
FORCEPROP 1 LAST PATH I85
J 0
(5125 6075);
DISPLAY 0.978723 (5125 6075);
DISPLAY INVISIBLE (5125 6075);
FORCEPROP 1 LAST PART_NUMBER CC72703MZ11
J 0
(5125 5725);
DISPLAY 0.510638 (5125 5725);
DISPLAY INVISIBLE (5125 5725);
FORCEADD Q_CAP..1
(4500 5925);
FORCEPROP 1 LAST LOCATION PC7001
J 0
(4550 6025);
DISPLAY 0.510638 (4550 6025);
FORCEPROP 0 LAST $SEC 1
J 0
(4550 6050);
DISPLAY 0.680851 (4550 6050);
PAINT MONO (4550 6050);
DISPLAY INVISIBLE (4550 6050);
FORCEPROP 0 LAST CDS_SEC 1
J 0
(4550 6050);
DISPLAY 0.680851 (4550 6050);
DISPLAY INVISIBLE (4550 6050);
FORCEPROP 1 LASTPIN (4500 6025) $PN 1
J 0
(4510 6005);
DISPLAY 0.787234 (4510 6005);
PAINT MONO (4510 6005);
FORCEPROP 1 LASTPIN (4500 5825) $PN 2
J 0
(4510 5805);
DISPLAY 0.787234 (4510 5805);
PAINT MONO (4510 5805);
FORCEPROP 1 LAST PACK_TYPE C0805
J 0
(4550 5725);
DISPLAY 0.510638 (4550 5725);
FORCEPROP 1 LAST VALUE 22UF
J 0
(4550 5975);
DISPLAY 0.510638 (4550 5975);
FORCEPROP 1 LAST VOLTAGE 16V
J 0
(4550 5925);
DISPLAY 0.510638 (4550 5925);
FORCEPROP 1 LAST TOLERANCE 20%
J 0
(4550 5875);
DISPLAY 0.510638 (4550 5875);
FORCEPROP 1 LAST MATERIAL X6S
J 0
(4550 5825);
DISPLAY 0.510638 (4550 5825);
FORCEPROP 2 LAST CDS_LIB pure_quanta
J 0
(4500 5925);
DISPLAY INVISIBLE (4500 5925);
FORCEPROP 1 LAST PATH I86
J 0
(4550 6075);
DISPLAY 0.978723 (4550 6075);
PAINT WHITE (4550 6075);
DISPLAY INVISIBLE (4550 6075);
FORCEPROP 1 LAST PART_NUMBER CH6223MEA01
J 0
(4550 5775);
DISPLAY 0.404255 (4550 5775);
DISPLAY INVISIBLE (4550 5775);
FORCEADD OFFPAGE..1
(1100 2150);
FORCEPROP 2 LAST $XR5 223 
J 0
(218 2150);
DISPLAY 0.638298 (218 2150);
PAINT MONO (218 2150);
FORCEPROP 2 LAST $XR4 222 
J 0
(338 2150);
DISPLAY 0.638298 (338 2150);
PAINT MONO (338 2150);
FORCEPROP 2 LAST $XR3 220 
J 0
(458 2150);
DISPLAY 0.638298 (458 2150);
PAINT MONO (458 2150);
FORCEPROP 2 LAST $XR2 219 
J 0
(578 2150);
DISPLAY 0.638298 (578 2150);
PAINT MONO (578 2150);
FORCEPROP 2 LAST $XR1 218 
J 0
(698 2150);
DISPLAY 0.638298 (698 2150);
PAINT MONO (698 2150);
FORCEPROP 2 LAST $XR0 217 
J 0
(818 2150);
DISPLAY 0.638298 (818 2150);
PAINT MONO (818 2150);
FORCEPROP 2 LAST CDS_LIB standard
J 0
(1100 2150);
DISPLAY INVISIBLE (1100 2150);
FORCEPROP 1 LAST OFFPAGE TRUE
J 0
(1425 2025);
DISPLAY 0.872340 (1425 2025);
PAINT GREEN (1425 2025);
DISPLAY INVISIBLE (1425 2025);
FORCEPROP 1 LAST COMMENT_BODY TRUE
J 0
(1225 2050);
DISPLAY 0.872340 (1225 2050);
PAINT GREEN (1225 2050);
DISPLAY INVISIBLE (1225 2050);
FORCEPROP 2 LAST PATH I9
J 0
(850 2200);
DISPLAY 0.680851 (850 2200);
DISPLAY INVISIBLE (850 2200);
FORCEADD DNS..1
(4125 4275);
PAINT RED (4125 4275);
FORCEPROP 2 LAST CDS_LIB mstr_misc
J 0
(4125 4275);
DISPLAY INVISIBLE (4125 4275);
FORCEPROP 1 LAST COMMENT_BODY TRUE
R 1
J 0
(4200 4050);
DISPLAY 0.872340 (4200 4050);
PAINT GREEN (4200 4050);
DISPLAY INVISIBLE (4200 4050);
FORCEADD DNS..1
(4000 1550);
PAINT RED (4000 1550);
FORCEPROP 2 LAST CDS_LIB mstr_misc
J 0
(4000 1550);
DISPLAY INVISIBLE (4000 1550);
FORCEPROP 1 LAST COMMENT_BODY TRUE
R 1
J 0
(4075 1325);
DISPLAY 0.872340 (4075 1325);
PAINT GREEN (4075 1325);
DISPLAY INVISIBLE (4075 1325);
FORCEADD DNS..1
(4150 4775);
PAINT RED (4150 4775);
FORCEPROP 2 LAST CDS_LIB mstr_misc
J 0
(4150 4775);
DISPLAY INVISIBLE (4150 4775);
FORCEPROP 1 LAST COMMENT_BODY TRUE
R 1
J 0
(4225 4550);
DISPLAY 0.872340 (4225 4550);
PAINT GREEN (4225 4550);
DISPLAY INVISIBLE (4225 4550);
FORCEADD DNS..1
(7800 3250);
PAINT RED (7800 3250);
FORCEPROP 2 LAST CDS_LIB mstr_misc
J 0
(7800 3250);
DISPLAY INVISIBLE (7800 3250);
FORCEPROP 1 LAST COMMENT_BODY TRUE
R 1
J 0
(7875 3025);
DISPLAY 0.872340 (7875 3025);
PAINT GREEN (7875 3025);
DISPLAY INVISIBLE (7875 3025);
FORCEADD DNS..1
(625 1725);
PAINT RED (625 1725);
FORCEPROP 2 LAST CDS_LIB mstr_misc
J 0
(625 1725);
PAINT MONO (625 1725);
DISPLAY INVISIBLE (625 1725);
FORCEPROP 1 LAST COMMENT_BODY TRUE
R 1
J 0
(700 1500);
DISPLAY 0.872340 (700 1500);
PAINT GREEN (700 1500);
DISPLAY INVISIBLE (700 1500);
FORCEADD DNS..1
(650 4525);
PAINT RED (650 4525);
FORCEPROP 2 LAST CDS_LIB mstr_misc
J 0
(650 4525);
PAINT MONO (650 4525);
DISPLAY INVISIBLE (650 4525);
FORCEPROP 1 LAST COMMENT_BODY TRUE
R 1
J 0
(725 4300);
DISPLAY 0.872340 (725 4300);
PAINT GREEN (725 4300);
DISPLAY INVISIBLE (725 4300);
FORCEADD DNS..1
(4000 2050);
PAINT RED (4000 2050);
FORCEPROP 2 LAST CDS_LIB mstr_misc
J 0
(4000 2050);
DISPLAY INVISIBLE (4000 2050);
FORCEPROP 1 LAST COMMENT_BODY TRUE
R 1
J 0
(4075 1825);
DISPLAY 0.872340 (4075 1825);
PAINT GREEN (4075 1825);
DISPLAY INVISIBLE (4075 1825);
FORCEADD QUANTA_TITLE_BLOCK_C..1
(8900 -100);
FORCEPROP 0 LAST CDS_CON_LAST_MODIFIED Thu Sep 14 16:12:42 2023
J 0
(7015 -85);
DISPLAY INVISIBLE (7015 -85);
FORCEPROP 1 LAST CUSTOM_TXT_CDS <CON_LAST_MODIFIED>
J 0
(7015 -85);
DISPLAY 0.978723 (7015 -85);
FORCEPROP 2 LAST CUSTOM_TXT_CDS <XR_PAGE_TITLE>
J 0
(1010 5150);
DISPLAY 0.638298 (1010 5150);
PAINT PINK (1010 5150);
DISPLAY INVISIBLE (1010 5150);
FORCEPROP 1 LAST CUSTOM_TXT_CDS <NAME_2>
J 0
(5725 -50);
FORCEPROP 1 LAST CUSTOM_TXT_CDS <NAME_1>
J 0
(5725 75);
FORCEPROP 1 LAST CUSTOM_TXT_CDS <Q_NUMBER>
J 0
(7497 3);
DISPLAY 1.212766 (7497 3);
FORCEPROP 1 LAST CUSTOM_TXT_CDS <Q_PROJ>
J 0
(6518 2);
DISPLAY 1.212766 (6518 2);
FORCEPROP 1 LAST CUSTOM_TXT_CDS <Q_REV>
J 0
(8716 3);
DISPLAY 1.212766 (8716 3);
FORCEPROP 1 LAST CUSTOM_TXT_CDS <CON_PAGE_NUM> OF <CON_TOTAL_PAGES>
J 0
(8454 -82);
DISPLAY 0.978723 (8454 -82);
FORCEPROP 1 LAST Q_TITLE PVDDIO_P1 VR PHASE 1&2
J 0
(-400 -50);
DISPLAY 2.446809 (-400 -50);
PAINT GREEN (-400 -50);
FORCEPROP 2 LAST CDS_LIB pure_quanta
J 0
(8900 -100);
DISPLAY INVISIBLE (8900 -100);
FORCEPROP 1 LAST CDS_LMAN_SYM_OUTLINE -9475,6775,100,-125
J 0
(8900 -100);
DISPLAY 0.468085 (8900 -100);
PAINT GREEN (8900 -100);
DISPLAY INVISIBLE (8900 -100);
FORCEPROP 2 LAST PAGE_BORDER TRUE
J 0
(1010 5150);
DISPLAY 0.638298 (1010 5150);
PAINT PINK (1010 5150);
DISPLAY INVISIBLE (1010 5150);
FORCEPROP 2 LAST CDS_XR_PAGE_TITLE CR-222 : @T6G_MB_LIB.T6G(SCH_1):PAGE222
J 0
(1010 5150);
DISPLAY 0.638298 (1010 5150);
PAINT PINK (1010 5150);
DISPLAY INVISIBLE (1010 5150);
FORCEPROP 1 LAST Q_DEPT BU9
J 1
(5137 -51);
DISPLAY 1.957447 (5137 -51);
PAINT GREEN (5137 -51);
DISPLAY INVISIBLE (5137 -51);
FORCEPROP 1 LAST COMMENT_BODY TRUE
J 0
(8912 -113);
DISPLAY 0.978723 (8912 -113);
PAINT GREEN (8912 -113);
DISPLAY INVISIBLE (8912 -113);
WIRE 16 -1 (100 1725)(100 1775);
WIRE 16 -1 (975 2550)(975 2500);
WIRE 16 -1 (1325 3125)(1325 3000);
WIRE 16 -1 (4025 1450)(4025 1375);
WIRE 16 -1 (100 4475)(100 4525);
WIRE 16 -1 (4125 4200)(4125 4125);
WIRE 16 -1 (650 4450)(650 4375);
WIRE 16 -1 (1075 5175)(1075 5125);
WIRE 16 -1 (1425 5750)(1425 5625);
WIRE 16 -1 (625 1650)(625 1575);
WIRE 16 -1 (5850 5850)(5850 5650);
WIRE 16 -1 (5850 6150)(5850 6225);
WIRE 16 -1 (5550 6150)(5850 6150);
WIRE 16 -1 (5850 6150)(5850 6050);
WIRE 16 -1 (3050 2600)(3825 2600);
FORCEPROP 2 LAST SIG_NAME SW_PVDDIO_P1_BOOT2
J 0
(3215 2610);
DISPLAY 0.489362 (3215 2610);
FORCEPROP 2 LASTPROP $XRERR UNIQUE?
J 0
(2975 2610);
DISPLAY 0.638298 (2975 2610);
PAINT MONO (2975 2610);
DISPLAY INVISIBLE (2975 2610);
WIRE 16 -1 (3225 3425)(3225 2900);
WIRE 16 -1 (3475 3425)(3225 3425);
WIRE 16 -1 (3225 2900)(3225 2850);
WIRE 16 -1 (3050 2900)(3225 2900);
WIRE 16 -1 (3225 2850)(3050 2850);
WIRE 16 -1 (3975 3425)(3475 3425);
WIRE 16 -1 (3475 3275)(3475 3425);
WIRE 16 -1 (3975 3425)(4375 3425);
WIRE 16 -1 (3975 3275)(3975 3425);
WIRE 16 -1 (4375 3425)(4775 3425);
WIRE 16 -1 (4375 3425)(4375 3275);
WIRE 16 -1 (5250 3425)(4775 3425);
WIRE 16 -1 (4775 3275)(4775 3425);
WIRE 16 -1 (5250 3500)(5250 3425);
WIRE 16 -1 (5250 3275)(5250 3425);
WIRE 16 -1 (2050 4900)(2050 4825);
FORCEPROP 0 LAST CDS_PHYS_NET_NAME PVDDCR_CPU1_P1_VCCS
J 0
(2050 4850);
PAINT MONO (2050 4850);
DISPLAY INVISIBLE (2050 4850);
WIRE 16 -1 (2050 4900)(2200 4900);
WIRE 16 -1 (1175 4900)(2050 4900);
FORCEPROP 2 LAST SIG_NAME PVDDCR_CPU1_P1_VCCS
J 0
(1240 4910);
DISPLAY 0.489362 (1240 4910);
WIRE 16 -1 (2050 4825)(100 4825);
WIRE 16 -1 (100 4825)(100 4725);
WIRE 16 -1 (3225 6150)(3225 5650);
WIRE 16 -1 (3325 6150)(3225 6150);
WIRE 16 -1 (3225 5650)(3225 5600);
WIRE 16 -1 (3050 5650)(3225 5650);
WIRE 16 -1 (3225 5600)(3050 5600);
WIRE 16 -1 (3675 6150)(3325 6150);
WIRE 16 -1 (3325 6025)(3325 6150);
WIRE 16 -1 (3675 6150)(4000 6150);
WIRE 16 -1 (3675 6000)(3675 6150);
WIRE 16 -1 (4250 6150)(4000 6150);
WIRE 16 -1 (4000 6150)(4000 6000);
WIRE 16 -1 (4500 6150)(4250 6150);
WIRE 16 -1 (4250 6000)(4250 6150);
WIRE 16 -1 (4650 6150)(4500 6150);
WIRE 16 -1 (4500 6150)(4500 6025);
WIRE 16 -1 (4650 6150)(4775 6150);
WIRE 16 -1 (4650 6200)(4650 6150);
WIRE 16 -1 (4775 6150)(5075 6150);
WIRE 16 -1 (4775 6150)(4775 6025);
WIRE 16 -1 (5075 6150)(5350 6150);
WIRE 16 -1 (5075 6025)(5075 6150);
WIRE 16 -1 (5250 3075)(5250 2925);
WIRE 16 -1 (5250 2875)(5250 2925);
WIRE 16 -1 (5250 2925)(4775 2925);
WIRE 16 -1 (4775 3075)(4775 2925);
WIRE 16 -1 (4375 2925)(4775 2925);
WIRE 16 -1 (4375 3075)(4375 2925);
WIRE 16 -1 (4375 2925)(3975 2925);
WIRE 16 -1 (3975 3075)(3975 2925);
WIRE 16 -1 (3475 2925)(3975 2925);
WIRE 16 -1 (3475 3075)(3475 2925);
WIRE 16 -1 (5075 4000)(3875 4000);
WIRE 16 -1 (3875 4750)(3875 4000);
WIRE 16 -1 (3050 4750)(3875 4750);
FORCEPROP 2 LAST SIG_NAME PVDDIO_P1_VOS1
J 0
(3165 4775);
DISPLAY 0.489362 (3165 4775);
FORCEPROP 2 LASTPROP $XRERR UNIQUE?
J 0
(2925 4775);
DISPLAY 0.638298 (2925 4775);
PAINT MONO (2925 4775);
DISPLAY INVISIBLE (2925 4775);
WIRE 16 -1 (5450 5000)(4125 5000);
WIRE 16 -1 (4125 5000)(4125 4900);
WIRE 16 -1 (4125 5000)(3050 5000);
FORCEPROP 2 LAST SIG_NAME SW_PVDDIO_P1_SW1
J 0
(3240 5010);
DISPLAY 0.489362 (3240 5010);
FORCEPROP 2 LASTPROP $XRERR UNIQUE?
J 0
(3000 5010);
DISPLAY 0.638298 (3000 5010);
PAINT MONO (3000 5010);
DISPLAY INVISIBLE (3000 5010);
WIRE 16 -1 (5000 5100)(5000 5125);
WIRE 16 -1 (3050 5100)(5000 5100);
FORCEPROP 2 LAST SIG_NAME SW_PVDDIO_P1_BOOTR1
J 0
(3240 5110);
DISPLAY 0.489362 (3240 5110);
FORCEPROP 2 LASTPROP $XRERR UNIQUE?
J 0
(3000 5110);
DISPLAY 0.638298 (3000 5110);
PAINT MONO (3000 5110);
DISPLAY INVISIBLE (3000 5110);
WIRE 16 -1 (3050 5350)(3875 5350);
FORCEPROP 2 LAST SIG_NAME SW_PVDDIO_P1_BOOT1
J 0
(3240 5360);
DISPLAY 0.489362 (3240 5360);
FORCEPROP 2 LASTPROP $XRERR UNIQUE?
J 0
(3000 5360);
DISPLAY 0.638298 (3000 5360);
PAINT MONO (3000 5360);
DISPLAY INVISIBLE (3000 5360);
WIRE 16 -1 (1650 2900)(2200 2900);
WIRE 16 -1 (1650 2900)(1650 3425);
WIRE 16 -1 (1650 3425)(1325 3425);
WIRE 16 -1 (1325 3325)(1325 3425);
WIRE 16 -1 (1325 3425)(975 3425);
WIRE 16 -1 (975 3550)(975 3425);
WIRE 16 -1 (975 3300)(975 3425);
WIRE 16 -1 (3050 1700)(3300 1700);
WIRE 16 -1 (3300 1750)(3300 1700);
WIRE 16 -1 (3300 1700)(3300 1650);
WIRE 16 -1 (3050 1650)(3300 1650);
WIRE 16 -1 (3300 1650)(3300 1575);
WIRE 16 -1 (3300 1750)(3300 1800);
WIRE 16 -1 (3050 1750)(3300 1750);
WIRE 16 -1 (3300 1800)(3050 1800);
WIRE 16 -1 (3050 4450)(3300 4450);
WIRE 16 -1 (3300 4500)(3300 4450);
WIRE 16 -1 (3300 4450)(3300 4400);
WIRE 16 -1 (3050 4400)(3300 4400);
WIRE 16 -1 (3300 4400)(3300 4325);
WIRE 16 -1 (3300 4500)(3300 4550);
WIRE 16 -1 (3050 4500)(3300 4500);
WIRE 16 -1 (3300 4550)(3050 4550);
WIRE 16 -1 (1750 5650)(2200 5650);
WIRE 16 -1 (1750 5650)(1750 6050);
WIRE 16 -1 (1750 6050)(1425 6050);
WIRE 16 -1 (1425 5950)(1425 6050);
WIRE 16 -1 (1425 6050)(1075 6050);
WIRE 16 -1 (1075 6175)(1075 6050);
WIRE 16 -1 (1075 5925)(1075 6050);
WIRE 16 -1 (7900 1950)(7900 1825);
WIRE 16 -1 (7900 1750)(7900 1825);
WIRE 16 -1 (7900 1825)(7475 1825);
WIRE 16 -1 (7475 1825)(7475 1950);
WIRE 16 -1 (7125 1225)(7125 2250);
WIRE 16 -1 (7125 1225)(5100 1225);
WIRE 16 -1 (7475 2250)(7125 2250);
WIRE 16 -1 (6425 2250)(7125 2250);
WIRE 16 -1 (7475 2250)(7900 2250);
WIRE 16 -1 (7475 2250)(7475 2150);
WIRE 16 -1 (7900 2350)(7900 2250);
WIRE 16 -1 (7900 2150)(7900 2250);
WIRE 16 -1 (7400 3175)(7400 3075);
WIRE 16 -1 (7400 3075)(7800 3075);
WIRE 16 -1 (7000 3075)(7400 3075);
WIRE 16 -1 (7000 3175)(7000 3075);
WIRE 16 -1 (7800 3175)(7800 3075);
WIRE 16 -1 (7800 3075)(7800 2975);
WIRE 16 -1 (7000 3375)(7000 3500);
WIRE 16 -1 (7000 3500)(7400 3500);
WIRE 16 -1 (7400 3500)(7800 3500);
WIRE 16 -1 (7400 3375)(7400 3500);
WIRE 16 -1 (7800 3550)(7800 3500);
WIRE 16 -1 (7800 3500)(7800 3375);
WIRE 16 -1 (6250 4750)(6775 4750);
WIRE 16 -1 (6775 4675)(6775 4750);
WIRE 16 -1 (7175 4700)(7175 4575);
WIRE 16 -1 (7500 4575)(7175 4575);
WIRE 16 -1 (7950 4575)(7500 4575);
WIRE 16 -1 (7500 4575)(7500 4700);
WIRE 16 -1 (8250 4575)(7950 4575);
WIRE 16 -1 (7950 4700)(7950 4575);
WIRE 16 -1 (8250 4700)(8250 4575);
WIRE 16 -1 (8250 4500)(8250 4575);
WIRE 16 -1 (7175 5000)(6975 5000);
WIRE 16 -1 (7500 5000)(7175 5000);
WIRE 16 -1 (7175 4900)(7175 5000);
WIRE 16 -1 (6975 5000)(6250 5000);
WIRE 16 -1 (6975 5000)(6975 4000);
WIRE 16 -1 (6975 4000)(5275 4000);
WIRE 16 -1 (7950 5000)(7500 5000);
WIRE 16 -1 (7500 5000)(7500 4900);
WIRE 16 -1 (8250 5000)(7950 5000);
WIRE 16 -1 (7950 4900)(7950 5000);
WIRE 16 -1 (8250 5050)(8250 5000);
WIRE 16 -1 (8250 5000)(8250 4900);
WIRE 16 -1 (5000 5350)(5000 5325);
WIRE 16 -1 (4075 5350)(5000 5350);
FORCEPROP 2 LAST SIG_NAME SW_PVDDIO_P1_BOOT1_R
J 0
(4365 5360);
DISPLAY 0.489362 (4365 5360);
FORCEPROP 2 LASTPROP $XRERR UNIQUE?
J 0
(4125 5360);
DISPLAY 0.638298 (4125 5360);
PAINT MONO (4125 5360);
DISPLAY INVISIBLE (4125 5360);
WIRE 16 -1 (4650 2600)(4650 2575);
WIRE 16 -1 (4025 2600)(4650 2600);
FORCEPROP 2 LAST SIG_NAME SW_PVDDIO_P1_BOOT2_R
J 0
(4240 2635);
DISPLAY 0.489362 (4240 2635);
FORCEPROP 2 LASTPROP $XRERR UNIQUE?
J 0
(4000 2635);
DISPLAY 0.638298 (4000 2635);
PAINT MONO (4000 2635);
DISPLAY INVISIBLE (4000 2635);
WIRE 16 -1 (4025 2150)(4025 2250);
WIRE 16 -1 (4025 2250)(5625 2250);
WIRE 16 -1 (3050 2250)(4025 2250);
FORCEPROP 2 LAST SIG_NAME SW_PVDDIO_P1_SW2
J 0
(3240 2260);
DISPLAY 0.489362 (3240 2260);
FORCEPROP 2 LASTPROP $XRERR UNIQUE?
J 0
(3000 2260);
DISPLAY 0.638298 (3000 2260);
PAINT MONO (3000 2260);
DISPLAY INVISIBLE (3000 2260);
WIRE 16 -1 (4650 2350)(4650 2375);
WIRE 16 -1 (3050 2350)(4650 2350);
FORCEPROP 2 LAST SIG_NAME SW_PVDDIO_P1_BOOTR2
J 0
(3240 2360);
DISPLAY 0.489362 (3240 2360);
FORCEPROP 2 LASTPROP $XRERR UNIQUE?
J 0
(3000 2360);
DISPLAY 0.638298 (3000 2360);
PAINT MONO (3000 2360);
DISPLAY INVISIBLE (3000 2360);
WIRE 16 -1 (2200 1750)(1150 1750);
FORCEPROP 2 LAST SIG_NAME PVDDIO_P1_TEMP1
J 0
(1215 1760);
DISPLAY 0.489362 (1215 1760);
WIRE 16 -1 (2200 1650)(1150 1650);
FORCEPROP 2 LAST SIG_NAME PVDDIO_P1_PWM2
J 0
(1215 1660);
DISPLAY 0.489362 (1215 1660);
WIRE 16 -1 (975 2825)(1375 2825);
WIRE 16 -1 (975 3100)(975 2825);
WIRE 16 -1 (975 2825)(975 2750);
WIRE 16 -1 (1375 2825)(1375 2600);
WIRE 16 -1 (2050 2600)(1375 2600);
FORCEPROP 0 LAST CDS_PHYS_NET_NAME PVDDIO_P1_VCC2
J 0
(1440 2640);
PAINT MONO (1440 2640);
DISPLAY INVISIBLE (1440 2640);
FORCEPROP 2 LAST SIG_NAME PVDDIO_P1_VCC2
J 0
(1415 2610);
DISPLAY 0.489362 (1415 2610);
FORCEPROP 2 LASTPROP $XRERR UNIQUE?
J 0
(1175 2610);
DISPLAY 0.638298 (1175 2610);
PAINT MONO (1175 2610);
DISPLAY INVISIBLE (1175 2610);
WIRE 16 -1 (2200 2600)(2050 2600);
WIRE 16 -1 (2050 2600)(2050 2400);
WIRE 16 -1 (2200 2400)(2050 2400);
WIRE 16 -1 (4125 4700)(4125 4400);
FORCEPROP 2 LAST SIG_NAME SW_PVDDIO_P1_SW1_RC
J 0
(4165 4510);
DISPLAY 0.489362 (4165 4510);
FORCEPROP 2 LASTPROP $XRERR UNIQUE?
J 0
(3925 4510);
DISPLAY 0.638298 (3925 4510);
PAINT MONO (3925 4510);
DISPLAY INVISIBLE (3925 4510);
WIRE 16 -1 (3050 4700)(3625 4700);
FORCEPROP 2 LAST SIG_NAME NC_PVDDIO_P1_GL1_1
J 0
(3165 4710);
DISPLAY 0.489362 (3165 4710);
FORCEPROP 2 LASTPROP $XRERR UNIQUE?
J 0
(3655 4700);
DISPLAY 0.638298 (3655 4700);
PAINT MONO (3655 4700);
DISPLAY INVISIBLE (3655 4700);
WIRE 16 -1 (650 4700)(2200 4700);
FORCEPROP 0 LAST CDS_PHYS_NET_NAME PVDDIO_P1_LSET1
J 0
(1240 4740);
PAINT MONO (1240 4740);
DISPLAY INVISIBLE (1240 4740);
FORCEPROP 2 LAST SIG_NAME PVDDIO_P1_LSET1
J 0
(1240 4710);
DISPLAY 0.489362 (1240 4710);
FORCEPROP 2 LASTPROP $XRERR UNIQUE?
J 0
(1000 4710);
DISPLAY 0.638298 (1000 4710);
PAINT MONO (1000 4710);
DISPLAY INVISIBLE (1000 4710);
WIRE 16 -1 (650 4700)(650 4650);
WIRE 16 -1 (1075 5450)(1650 5450);
WIRE 16 -1 (1075 5725)(1075 5450);
WIRE 16 -1 (1075 5450)(1075 5375);
WIRE 16 -1 (1650 5450)(1650 5350);
WIRE 16 -1 (2050 5350)(1650 5350);
FORCEPROP 0 LAST CDS_PHYS_NET_NAME PVDDIO_P1_VCC1
J 0
(1740 5390);
PAINT MONO (1740 5390);
DISPLAY INVISIBLE (1740 5390);
FORCEPROP 2 LAST SIG_NAME PVDDIO_P1_VCC1
J 0
(1715 5360);
DISPLAY 0.489362 (1715 5360);
FORCEPROP 2 LASTPROP $XRERR UNIQUE?
J 0
(1475 5360);
DISPLAY 0.638298 (1475 5360);
PAINT MONO (1475 5360);
DISPLAY INVISIBLE (1475 5360);
WIRE 16 -1 (2200 5350)(2050 5350);
WIRE 16 -1 (2050 5350)(2050 5150);
WIRE 16 -1 (2200 5150)(2050 5150);
WIRE 16 -1 (2200 4500)(1175 4500);
FORCEPROP 2 LAST SIG_NAME PVDDIO_P1_TEMP1
J 0
(1240 4510);
DISPLAY 0.489362 (1240 4510);
WIRE 16 -1 (2200 5000)(1175 5000);
FORCEPROP 2 LAST SIG_NAME PVDDIO_P1_IMON1
J 0
(1240 5010);
DISPLAY 0.489362 (1240 5010);
WIRE 16 -1 (4900 4750)(5450 4750);
FORCEPROP 2 LAST SIG_NAME IND_PVDDIO_P1_CPL2
J 0
(4965 4760);
DISPLAY 0.489362 (4965 4760);
WIRE 17 273 (6675 3700)(8175 3700);
WIRE 17 273 (6675 2825)(6675 3700);
WIRE 17 273 (8175 3700)(8175 2825);
WIRE 17 273 (6675 2825)(8175 2825);
WIRE 16 -1 (6425 2000)(6850 2000);
FORCEPROP 2 LAST SIG_NAME IND_PVDDIO_P1_CPL2
J 0
(6465 2010);
DISPLAY 0.489362 (6465 2010);
WIRE 16 -1 (5125 2000)(5625 2000);
FORCEPROP 2 LAST SIG_NAME IND_PVDDIO_P1_CPL3
J 0
(5140 2010);
DISPLAY 0.489362 (5140 2010);
WIRE 16 -1 (3625 4650)(3050 4650);
FORCEPROP 2 LAST SIG_NAME NC_PVDDIO_P1_GL2_1
J 0
(3165 4660);
DISPLAY 0.489362 (3165 4660);
FORCEPROP 2 LASTPROP $XRERR UNIQUE?
J 0
(3655 4650);
DISPLAY 0.638298 (3655 4650);
PAINT MONO (3655 4650);
DISPLAY INVISIBLE (3655 4650);
WIRE 16 -1 (2200 4400)(1175 4400);
FORCEPROP 2 LAST SIG_NAME PVDDIO_P1_PWM1
J 0
(1240 4410);
DISPLAY 0.489362 (1240 4410);
WIRE 16 -1 (2200 4750)(1775 4750);
FORCEPROP 2 LAST SIG_NAME NC_PVDDIO_P1_DNC1
J 0
(1755 4760);
DISPLAY 0.489362 (1755 4760);
FORCEPROP 2 LASTPROP $XRERR UNIQUE?
J 0
(1535 4750);
DISPLAY 0.638298 (1535 4750);
PAINT MONO (1535 4750);
DISPLAY INVISIBLE (1535 4750);
WIRE 16 -1 (4025 1950)(4025 1650);
FORCEPROP 2 LAST SIG_NAME SW_PVDDIO_P1_SW2_RC
J 0
(4065 1760);
DISPLAY 0.489362 (4065 1760);
FORCEPROP 2 LASTPROP $XRERR UNIQUE?
J 0
(3825 1760);
DISPLAY 0.638298 (3825 1760);
PAINT MONO (3825 1760);
DISPLAY INVISIBLE (3825 1760);
WIRE 16 -1 (4900 1225)(3800 1225);
WIRE 16 -1 (3800 2000)(3800 1225);
WIRE 16 -1 (3050 2000)(3800 2000);
FORCEPROP 2 LAST SIG_NAME PVDDIO_P1_VOS2
J 0
(3240 2025);
DISPLAY 0.489362 (3240 2025);
FORCEPROP 2 LASTPROP $XRERR UNIQUE?
J 0
(3000 2025);
DISPLAY 0.638298 (3000 2025);
PAINT MONO (3000 2025);
DISPLAY INVISIBLE (3000 2025);
WIRE 16 -1 (3050 1950)(3625 1950);
FORCEPROP 2 LAST SIG_NAME NC_PVDDIO_P1_GL1_2
J 0
(3240 1960);
DISPLAY 0.489362 (3240 1960);
FORCEPROP 2 LASTPROP $XRERR UNIQUE?
J 0
(3655 1950);
DISPLAY 0.638298 (3655 1950);
PAINT MONO (3655 1950);
DISPLAY INVISIBLE (3655 1950);
WIRE 16 -1 (3050 1900)(3625 1900);
FORCEPROP 2 LAST SIG_NAME NC_PVDDIO_P1_GL2_2
J 0
(3240 1910);
DISPLAY 0.489362 (3240 1910);
FORCEPROP 2 LASTPROP $XRERR UNIQUE?
J 0
(3655 1900);
DISPLAY 0.638298 (3655 1900);
PAINT MONO (3655 1900);
DISPLAY INVISIBLE (3655 1900);
WIRE 16 -1 (2200 2250)(1150 2250);
FORCEPROP 2 LAST SIG_NAME PVDDIO_P1_IMON2
J 0
(1215 2260);
DISPLAY 0.489362 (1215 2260);
WIRE 16 -1 (1775 2000)(2200 2000);
FORCEPROP 2 LAST SIG_NAME NC_PVDDIO_P1_DNC2
J 0
(1705 2010);
DISPLAY 0.489362 (1705 2010);
FORCEPROP 2 LASTPROP $XRERR UNIQUE?
J 0
(1535 2000);
DISPLAY 0.638298 (1535 2000);
PAINT MONO (1535 2000);
DISPLAY INVISIBLE (1535 2000);
WIRE 16 -1 (2050 2150)(2050 2075);
FORCEPROP 0 LAST CDS_PHYS_NET_NAME PVDDCR_CPU1_P1_VCCS
J 0
(2050 2100);
PAINT MONO (2050 2100);
DISPLAY INVISIBLE (2050 2100);
WIRE 16 -1 (2050 2150)(2200 2150);
WIRE 16 -1 (1150 2150)(2050 2150);
FORCEPROP 2 LAST SIG_NAME PVDDCR_CPU1_P1_VCCS
J 0
(1215 2160);
DISPLAY 0.489362 (1215 2160);
WIRE 16 -1 (2050 2075)(100 2075);
WIRE 16 -1 (100 2075)(100 1975);
WIRE 16 -1 (625 1950)(2200 1950);
FORCEPROP 2 LAST SIG_NAME PVDDIO_P1_LSET2
J 0
(1215 1960);
DISPLAY 0.489362 (1215 1960);
FORCEPROP 2 LASTPROP $XRERR UNIQUE?
J 0
(975 1960);
DISPLAY 0.638298 (975 1960);
PAINT MONO (975 1960);
DISPLAY INVISIBLE (975 1960);
WIRE 16 -1 (625 1950)(625 1850);
WIRE 16 -1 (3325 5825)(3325 5650);
WIRE 16 -1 (3325 5650)(3675 5650);
WIRE 16 -1 (3675 5650)(4000 5650);
WIRE 16 -1 (3675 5800)(3675 5650);
WIRE 16 -1 (4250 5650)(4000 5650);
WIRE 16 -1 (4000 5800)(4000 5650);
WIRE 16 -1 (4500 5650)(4250 5650);
WIRE 16 -1 (4250 5800)(4250 5650);
WIRE 16 -1 (4650 5650)(4500 5650);
WIRE 16 -1 (4500 5825)(4500 5650);
WIRE 16 -1 (4650 5650)(4775 5650);
WIRE 16 -1 (4650 5575)(4650 5650);
WIRE 16 -1 (4775 5650)(5075 5650);
WIRE 16 -1 (4775 5825)(4775 5650);
WIRE 16 -1 (5075 5650)(5075 5825);
DOT 1 (3225 2900);
DOT 1 (4650 5650);
DOT 1 (4250 5650);
DOT 1 (4250 6150);
DOT 1 (4775 5650);
DOT 1 (4000 5650);
DOT 1 (4000 6150);
DOT 1 (3675 5650);
DOT 1 (3675 6150);
DOT 1 (3325 6150);
DOT 1 (8250 5000);
DOT 1 (7950 5000);
DOT 1 (8250 4575);
DOT 1 (7950 4575);
DOT 1 (7500 5000);
DOT 1 (7500 4575);
DOT 1 (7175 5000);
DOT 1 (6975 5000);
DOT 1 (5850 6150);
DOT 1 (4650 6150);
DOT 1 (7800 3500);
DOT 1 (7400 3500);
DOT 1 (7800 3075);
DOT 1 (7400 3075);
DOT 1 (7125 2250);
DOT 1 (7475 2250);
DOT 1 (7900 2250);
DOT 1 (7900 1825);
DOT 1 (5250 3425);
DOT 1 (5250 2925);
DOT 1 (4775 3425);
DOT 1 (4375 3425);
DOT 1 (4775 2925);
DOT 1 (4375 2925);
DOT 1 (3225 5650);
DOT 1 (4125 5000);
DOT 1 (3300 4500);
DOT 1 (3300 4450);
DOT 1 (3300 4400);
DOT 1 (2050 5350);
DOT 1 (1425 6050);
DOT 1 (2050 4900);
DOT 1 (1075 6050);
DOT 1 (1075 5450);
DOT 1 (3975 3425);
DOT 1 (3475 3425);
DOT 1 (3975 2925);
DOT 1 (4025 2250);
DOT 1 (3300 1750);
DOT 1 (3300 1700);
DOT 1 (3300 1650);
DOT 1 (1325 3425);
DOT 1 (2050 2600);
DOT 1 (975 3425);
DOT 1 (975 2825);
DOT 1 (2050 2150);
DOT 1 (5075 6150);
DOT 1 (4500 6150);
DOT 1 (4500 5650);
DOT 1 (4775 6150);
FORCENOTE
MAIN SOURCE:RENESAS BOM
(-275 1200) 0;
DISPLAY LEFT (-275 1200);
DISPLAY 1.021277 (-275 1200);
PAINT WHITE (-275 1200);
FORCENOTE
PU39,PU40,PU52,PU53 = AL099390004/ISL99390FRZ-TR5935
(-275 1125) 0;
DISPLAY LEFT (-275 1125);
DISPLAY 1.021277 (-275 1125);
PAINT WHITE (-275 1125);
FORCENOTE
2ND SOURCE:INFENEON BOM
(-275 1000) 0;
DISPLAY LEFT (-275 1000);
DISPLAY 1.021277 (-275 1000);
PAINT WHITE (-275 1000);
FORCENOTE
PU39,PU40,PU52,PU53 = AL021590000/TDA21590
(-275 925) 0;
DISPLAY LEFT (-275 925);
DISPLAY 1.021277 (-275 925);
PAINT WHITE (-275 925);
FORCENOTE
PR372,PR373,PR278,PR279 = CS00002JB13
(-275 850) 0;
DISPLAY LEFT (-275 850);
DISPLAY 1.021277 (-275 850);
PAINT WHITE (-275 850);
FORCENOTE
PR275,PR274,PR369,PR368 = CS00002JB13
(-275 775) 0;
DISPLAY LEFT (-275 775);
DISPLAY 1.021277 (-275 775);
PAINT WHITE (-275 775);
FORCENOTE
PR280,PR281,PR374,PR375 = EMPTY
(-275 700) 0;
DISPLAY LEFT (-275 700);
DISPLAY 1.021277 (-275 700);
PAINT WHITE (-275 700);
FORCENOTE
PC435_7,PC436_8,PC620_9,PC621_10 = EMPTY
(-275 625) 0;
DISPLAY LEFT (-275 625);
DISPLAY 1.021277 (-275 625);
PAINT WHITE (-275 625);
FORCENOTE
PU39,PU40,PU52,PU53=AL087000A03/MP87000GMJTH-C11D-Z
(-275 425) 0;
DISPLAY LEFT (-275 425);
DISPLAY 1.021277 (-275 425);
PAINT WHITE (-275 425);
FORCENOTE
BOM NOTE
(-275 1300) 0;
DISPLAY LEFT (-275 1300);
DISPLAY 1.021277 (-275 1300);
PAINT WHITE (-275 1300);
FORCENOTE
PR278,PR279,PR372,PR373=CS00002JB13
(-275 350) 0;
DISPLAY LEFT (-275 350);
DISPLAY 1.021277 (-275 350);
PAINT WHITE (-275 350);
FORCENOTE
PC435_7,PC436_8,PC620_9,PC621_10=EMPTY
(-275 200) 0;
DISPLAY LEFT (-275 200);
DISPLAY 1.021277 (-275 200);
PAINT WHITE (-275 200);
FORCENOTE
DCR=1-4,0.105M OHM
(6425 2425) 0;
DISPLAY LEFT (6425 2425);
DISPLAY 0.638298 (6425 2425);
PAINT WHITE (6425 2425);
FORCENOTE
DCR=1-4,0.105M OHM
(6250 5175) 0;
DISPLAY LEFT (6250 5175);
DISPLAY 0.638298 (6250 5175);
PAINT WHITE (6250 5175);
FORCENOTE
PGL6303.151HLT
(6250 5325) 0;
DISPLAY LEFT (6250 5325);
DISPLAY 0.638298 (6250 5325);
PAINT WHITE (6250 5325);
FORCENOTE
DCR=2-3,0.27M OHM
(6250 5125) 0;
DISPLAY LEFT (6250 5125);
DISPLAY 0.638298 (6250 5125);
PAINT WHITE (6250 5125);
FORCENOTE
2ND=CV+15^0TZ01
(6250 5075) 0;
DISPLAY LEFT (6250 5075);
DISPLAY 0.638298 (6250 5075);
PAINT WHITE (6250 5075);
FORCENOTE
ISAT:70A@100C
(6250 5275) 0;
DISPLAY LEFT (6250 5275);
DISPLAY 0.638298 (6250 5275);
PAINT WHITE (6250 5275);
FORCENOTE
11.0*7.5*12.5
(6250 5225) 0;
DISPLAY LEFT (6250 5225);
DISPLAY 0.638298 (6250 5225);
PAINT WHITE (6250 5225);
FORCENOTE
6.3*8
(5125 5575) 0;
DISPLAY LEFT (5125 5575);
DISPLAY 0.638298 (5125 5575);
PAINT WHITE (5125 5575);
FORCENOTE
IRIPPLE:5.08A
(5125 5625) 0;
DISPLAY LEFT (5125 5625);
DISPLAY 0.638298 (5125 5625);
PAINT WHITE (5125 5625);
FORCENOTE
7.3*4.3*1.9
(7225 2925) 0;
DISPLAY LEFT (7225 2925);
DISPLAY 0.638298 (7225 2925);
PAINT WHITE (7225 2925);
FORCENOTE
ESR=4.5M OHM
(7225 2975) 0;
DISPLAY LEFT (7225 2975);
DISPLAY 0.638298 (7225 2975);
PAINT WHITE (7225 2975);
FORCENOTE
2ND=CH747LM8822
(7225 2875) 0;
DISPLAY LEFT (7225 2875);
DISPLAY 0.638298 (7225 2875);
PAINT WHITE (7225 2875);
FORCENOTE
11.0*7.5*12.5
(6425 2475) 0;
DISPLAY LEFT (6425 2475);
DISPLAY 0.638298 (6425 2475);
PAINT WHITE (6425 2475);
FORCENOTE
ISAT:70A@100C
(6425 2525) 0;
DISPLAY LEFT (6425 2525);
DISPLAY 0.638298 (6425 2525);
PAINT WHITE (6425 2525);
FORCENOTE
PGL6303.151HLT
(6425 2575) 0;
DISPLAY LEFT (6425 2575);
DISPLAY 0.638298 (6425 2575);
PAINT WHITE (6425 2575);
FORCENOTE
DCR=2-3,0.27M OHM
(6425 2375) 0;
DISPLAY LEFT (6425 2375);
DISPLAY 0.638298 (6425 2375);
PAINT WHITE (6425 2375);
FORCENOTE
2ND=CV+15^0TZ01
(6425 2325) 0;
DISPLAY LEFT (6425 2325);
DISPLAY 0.638298 (6425 2325);
PAINT WHITE (6425 2325);
FORCENOTE
PVDDIO_P1_PHASE2
(2350 3325) 0;
DISPLAY LEFT (2350 3325);
DISPLAY 1.021277 (2350 3325);
PAINT WHITE (2350 3325);
FORCENOTE
3RD SOURCE:MPS BOM
(-275 500) 0;
DISPLAY LEFT (-275 500);
DISPLAY 1.021277 (-275 500);
PAINT WHITE (-275 500);
FORCENOTE
PR280,PR281,PR374,PR375=EMPTY
(-275 275) 0;
DISPLAY LEFT (-275 275);
DISPLAY 1.021277 (-275 275);
PAINT WHITE (-275 275);
FORCENOTE
PVDDIO_P1_PHASE1
(2350 6100) 0;
DISPLAY LEFT (2350 6100);
DISPLAY 1.021277 (2350 6100);
PAINT WHITE (2350 6100);
FORCENOTE
2ND=CC72703MD39
(5125 5525) 0;
DISPLAY LEFT (5125 5525);
DISPLAY 0.638298 (5125 5525);
PAINT WHITE (5125 5525);
FORCENOTE
ESR=10M OHM
(5125 5675) 0;
DISPLAY LEFT (5125 5675);
DISPLAY 0.638298 (5125 5675);
PAINT WHITE (5125 5675);
FORCENOTE
3RD=CVA50^0MZ08
(5300 5825) 0;
DISPLAY LEFT (5300 5825);
DISPLAY 0.638298 (5300 5825);
PAINT WHITE (5300 5825);
FORCENOTE
2ND=CVA50^0MZ07
(5300 5875) 0;
DISPLAY LEFT (5300 5875);
DISPLAY 0.638298 (5300 5875);
PAINT WHITE (5300 5875);
FORCENOTE
DCR=0.09M OHM
(5300 5925) 0;
DISPLAY LEFT (5300 5925);
DISPLAY 0.638298 (5300 5925);
PAINT WHITE (5300 5925);
FORCENOTE
ISAT:70A@100C
(5300 6025) 0;
DISPLAY LEFT (5300 6025);
DISPLAY 0.638298 (5300 6025);
PAINT WHITE (5300 6025);
FORCENOTE
PG2292.500HLT
(5300 6075) 0;
DISPLAY LEFT (5300 6075);
DISPLAY 0.638298 (5300 6075);
PAINT WHITE (5300 6075);
FORCENOTE
6.0*6.1*7.0
(5300 5975) 0;
DISPLAY LEFT (5300 5975);
DISPLAY 0.638298 (5300 5975);
PAINT WHITE (5300 5975);
QUIT
